FILE_TYPE = MACRO_DRAWING;
SET COLOR_WIRE YELLOW;
SET COLOR_PROP ORANGE;
SET COLOR_DOT WHITE;
SET COLOR_ARC YELLOW;
SET COLOR_BODY GREEN;
SET COLOR_NOTE PURPLE;
SET PROP_DISPLAY VALUE;
SET PAGE_NUMBER P256;
FORCEADD UNIVERSAL_GND..1
(-7550 -6125);
FORCEPROP 3 LASTPIN (-7550 -6075) SIG_NAME GND\g
J 0
(-7540 -6065);
DISPLAY 0.659574 (-7540 -6065);
PAINT MONO (-7540 -6065);
DISPLAY INVISIBLE (-7540 -6065);
FORCEPROP 2 LAST CDS_LIB logical_power
J 0
(-7550 -6125);
PAINT MONO (-7550 -6125);
DISPLAY INVISIBLE (-7550 -6125);
FORCEPROP 1 LAST HDL_POWER GND
J 1
(-7525 -6200);
DISPLAY 0.872340 (-7525 -6200);
PAINT GREEN (-7525 -6200);
DISPLAY INVISIBLE (-7525 -6200);
FORCEPROP 1 LAST PATH I1
J 0
(-7475 -6125);
DISPLAY 0.872340 (-7475 -6125);
PAINT AQUA (-7475 -6125);
DISPLAY INVISIBLE (-7475 -6125);
FORCEPROP 2 LAST ROOM VR_CORE0_CTRL
J 0
(-7822 -6003);
DISPLAY INVISIBLE (-7822 -6003);
FORCEADD UNIVERSAL_GND..1
(-7150 -5150);
FORCEPROP 3 LASTPIN (-7150 -5100) SIG_NAME GND\g
J 0
(-7140 -5090);
DISPLAY 0.659574 (-7140 -5090);
PAINT MONO (-7140 -5090);
DISPLAY INVISIBLE (-7140 -5090);
FORCEPROP 2 LAST CDS_LIB logical_power
J 0
(-7150 -5150);
PAINT MONO (-7150 -5150);
DISPLAY INVISIBLE (-7150 -5150);
FORCEPROP 1 LAST HDL_POWER GND
J 1
(-7125 -5225);
DISPLAY 0.872340 (-7125 -5225);
PAINT GREEN (-7125 -5225);
DISPLAY INVISIBLE (-7125 -5225);
FORCEPROP 1 LAST PATH I10
J 0
(-7075 -5150);
DISPLAY 0.872340 (-7075 -5150);
PAINT AQUA (-7075 -5150);
DISPLAY INVISIBLE (-7075 -5150);
FORCEPROP 2 LAST ROOM VR_CORE0_CTRL
J 0
(-7422 -5028);
DISPLAY INVISIBLE (-7422 -5028);
FORCEADD Q_CAP..1
(-7150 -4900);
FORCEPROP 1 LAST PART_NUMBER CH5222KEB01
J 0
(-7100 -5075);
DISPLAY 0.617021 (-7100 -5075);
PAINT BLUE (-7100 -5075);
DISPLAY INVISIBLE (-7100 -5075);
FORCEPROP 1 LAST MATERIAL X6S
J 0
(-7100 -4975);
DISPLAY 0.617021 (-7100 -4975);
PAINT SKYBLUE (-7100 -4975);
FORCEPROP 1 LAST TOLERANCE 10%
J 0
(-7100 -4925);
DISPLAY 0.617021 (-7100 -4925);
PAINT SKYBLUE (-7100 -4925);
FORCEPROP 1 LAST VALUE 2.2UF
J 0
(-7100 -4825);
DISPLAY 0.617021 (-7100 -4825);
PAINT SKYBLUE (-7100 -4825);
FORCEPROP 1 LAST VOLTAGE 10V
J 0
(-7100 -4875);
DISPLAY 0.617021 (-7100 -4875);
PAINT SKYBLUE (-7100 -4875);
FORCEPROP 1 LAST PACK_TYPE C0402
J 0
(-7100 -5025);
DISPLAY 0.617021 (-7100 -5025);
PAINT SKYBLUE (-7100 -5025);
FORCEPROP 1 LAST LOCATION PC226
J 0
(-7100 -4775);
DISPLAY 0.617021 (-7100 -4775);
PAINT AQUA (-7100 -4775);
FORCEPROP 1 LASTPIN (-7150 -4800) $PN 1
J 0
(-7140 -4820);
DISPLAY 0.617021 (-7140 -4820);
PAINT MONO (-7140 -4820);
FORCEPROP 1 LASTPIN (-7150 -5000) $PN 2
J 0
(-7140 -5020);
DISPLAY 0.617021 (-7140 -5020);
PAINT MONO (-7140 -5020);
FORCEPROP 2 LAST CDS_LIB pure_quanta
J 0
(-7150 -4900);
DISPLAY INVISIBLE (-7150 -4900);
FORCEPROP 1 LAST PATH I11
J 0
(-7100 -4750);
DISPLAY 0.978723 (-7100 -4750);
PAINT WHITE (-7100 -4750);
DISPLAY INVISIBLE (-7100 -4750);
FORCEPROP 1 LAST LOCATION PC226
J 0
(-7100 -4725);
DISPLAY 1.021277 (-7100 -4725);
PAINT AQUA (-7100 -4725);
DISPLAY INVISIBLE (-7100 -4725);
FORCEPROP 0 LAST $SEC 1
J 0
(-7100 -4725);
DISPLAY 0.680851 (-7100 -4725);
PAINT MONO (-7100 -4725);
DISPLAY INVISIBLE (-7100 -4725);
FORCEPROP 0 LAST CDS_SEC 1
J 0
(-7100 -4725);
DISPLAY 1.021277 (-7100 -4725);
DISPLAY INVISIBLE (-7100 -4725);
FORCEADD Q_RES..2
(-7150 -4400);
FORCEPROP 1 LAST PART_NUMBER CS-2202FB01
J 0
(-7110 -4525);
DISPLAY 0.617021 (-7110 -4525);
PAINT BLUE (-7110 -4525);
DISPLAY INVISIBLE (-7110 -4525);
FORCEPROP 1 LAST PACK_TYPE 0402LF
J 0
(-7110 -4575);
DISPLAY 0.617021 (-7110 -4575);
PAINT SKYBLUE (-7110 -4575);
FORCEPROP 1 LAST WATTAGE 1/16W
J 0
(-7110 -4425);
DISPLAY 0.617021 (-7110 -4425);
PAINT SKYBLUE (-7110 -4425);
FORCEPROP 1 LAST MATERIAL CHIP
J 0
(-7110 -4475);
DISPLAY 0.617021 (-7110 -4475);
PAINT SKYBLUE (-7110 -4475);
FORCEPROP 1 LAST TOLERANCE 1%
J 0
(-7105 -4375);
DISPLAY 0.617021 (-7105 -4375);
PAINT SKYBLUE (-7105 -4375);
FORCEPROP 1 LAST VALUE 2.2
J 0
(-7105 -4325);
DISPLAY 0.617021 (-7105 -4325);
PAINT SKYBLUE (-7105 -4325);
FORCEPROP 1 LAST LOCATION PR134
J 0
(-7105 -4275);
DISPLAY 0.617021 (-7105 -4275);
PAINT AQUA (-7105 -4275);
FORCEPROP 1 LASTPIN (-7150 -4300) $PN 1
J 0
(-7145 -4338);
DISPLAY 0.617021 (-7145 -4338);
PAINT MONO (-7145 -4338);
FORCEPROP 1 LASTPIN (-7150 -4500) $PN 2
J 0
(-7145 -4490);
DISPLAY 0.617021 (-7145 -4490);
PAINT MONO (-7145 -4490);
FORCEPROP 2 LAST CDS_LIB pure_quanta
J 0
(-7150 -4400);
DISPLAY INVISIBLE (-7150 -4400);
FORCEPROP 1 LAST PATH I12
J 0
(-7100 -4225);
DISPLAY 0.978723 (-7100 -4225);
PAINT WHITE (-7100 -4225);
DISPLAY INVISIBLE (-7100 -4225);
FORCEPROP 1 LAST LOCATION PR134
J 0
(-7100 -4225);
DISPLAY 1.021277 (-7100 -4225);
PAINT AQUA (-7100 -4225);
DISPLAY INVISIBLE (-7100 -4225);
FORCEPROP 0 LAST $SEC 1
J 0
(-7100 -4225);
DISPLAY 0.680851 (-7100 -4225);
PAINT MONO (-7100 -4225);
DISPLAY INVISIBLE (-7100 -4225);
FORCEPROP 0 LAST CDS_SEC 1
J 0
(-7100 -4225);
DISPLAY 1.021277 (-7100 -4225);
DISPLAY INVISIBLE (-7100 -4225);
FORCEADD VCC15..1
(-7150 -4075);
FORCEPROP 3 LASTPIN (-7150 -4125) SIG_NAME PVCCIN_CPU0_PVCC\g
J 0
(-7140 -4115);
DISPLAY 0.659574 (-7140 -4115);
PAINT MONO (-7140 -4115);
DISPLAY INVISIBLE (-7140 -4115);
FORCEPROP 1 LAST HDL_POWER PVCCIN_CPU0_PVCC
J 1
(-7150 -4025);
DISPLAY 0.617021 (-7150 -4025);
PAINT GREEN (-7150 -4025);
FORCEPROP 2 LAST CDS_LIB logical_power
J 0
(-7150 -4075);
DISPLAY INVISIBLE (-7150 -4075);
FORCEPROP 1 LAST PATH I13
J 0
(-7100 -4050);
DISPLAY 0.872340 (-7100 -4050);
PAINT AQUA (-7100 -4050);
DISPLAY INVISIBLE (-7100 -4050);
FORCEADD UNIVERSAL_GND..1
(-6725 -4625);
FORCEPROP 3 LASTPIN (-6725 -4575) SIG_NAME GND\g
J 0
(-6715 -4565);
DISPLAY 0.659574 (-6715 -4565);
PAINT MONO (-6715 -4565);
DISPLAY INVISIBLE (-6715 -4565);
FORCEPROP 2 LAST CDS_LIB logical_power
J 0
(-6725 -4625);
PAINT MONO (-6725 -4625);
DISPLAY INVISIBLE (-6725 -4625);
FORCEPROP 1 LAST HDL_POWER GND
J 1
(-6700 -4700);
DISPLAY 0.872340 (-6700 -4700);
PAINT GREEN (-6700 -4700);
DISPLAY INVISIBLE (-6700 -4700);
FORCEPROP 1 LAST PATH I14
J 0
(-6650 -4625);
DISPLAY 0.872340 (-6650 -4625);
PAINT AQUA (-6650 -4625);
DISPLAY INVISIBLE (-6650 -4625);
FORCEPROP 2 LAST ROOM VR_CORE0_CTRL
J 0
(-6997 -4503);
DISPLAY INVISIBLE (-6997 -4503);
FORCEADD Q_CAP..1
(-6725 -4400);
FORCEPROP 1 LAST PART_NUMBER CH5222KEB01
J 0
(-6675 -4525);
DISPLAY 0.617021 (-6675 -4525);
PAINT BLUE (-6675 -4525);
DISPLAY INVISIBLE (-6675 -4525);
FORCEPROP 1 LAST MATERIAL X6S
J 0
(-6675 -4475);
DISPLAY 0.617021 (-6675 -4475);
PAINT SKYBLUE (-6675 -4475);
FORCEPROP 1 LAST TOLERANCE 10%
J 0
(-6675 -4425);
DISPLAY 0.617021 (-6675 -4425);
PAINT SKYBLUE (-6675 -4425);
FORCEPROP 1 LAST VALUE 2.2UF
J 0
(-6675 -4325);
DISPLAY 0.617021 (-6675 -4325);
PAINT SKYBLUE (-6675 -4325);
FORCEPROP 1 LAST VOLTAGE 10V
J 0
(-6675 -4375);
DISPLAY 0.617021 (-6675 -4375);
PAINT SKYBLUE (-6675 -4375);
FORCEPROP 1 LAST PACK_TYPE C0402
J 0
(-6675 -4575);
DISPLAY 0.617021 (-6675 -4575);
PAINT SKYBLUE (-6675 -4575);
FORCEPROP 1 LAST LOCATION PC228_P0_8
J 0
(-6675 -4275);
DISPLAY 0.617021 (-6675 -4275);
PAINT AQUA (-6675 -4275);
FORCEPROP 1 LASTPIN (-6725 -4300) $PN 1
J 0
(-6715 -4320);
DISPLAY 0.617021 (-6715 -4320);
PAINT MONO (-6715 -4320);
FORCEPROP 1 LASTPIN (-6725 -4500) $PN 2
J 0
(-6715 -4520);
DISPLAY 0.617021 (-6715 -4520);
PAINT MONO (-6715 -4520);
FORCEPROP 2 LAST CDS_LIB pure_quanta
J 0
(-6725 -4400);
DISPLAY INVISIBLE (-6725 -4400);
FORCEPROP 1 LAST PATH I15
J 0
(-6675 -4250);
DISPLAY 0.978723 (-6675 -4250);
PAINT WHITE (-6675 -4250);
DISPLAY INVISIBLE (-6675 -4250);
FORCEPROP 1 LAST LOCATION PC228_P0_8
J 0
(-6675 -4225);
DISPLAY 1.021277 (-6675 -4225);
PAINT AQUA (-6675 -4225);
DISPLAY INVISIBLE (-6675 -4225);
FORCEPROP 0 LAST $SEC 1
J 0
(-6675 -4225);
DISPLAY 0.680851 (-6675 -4225);
PAINT MONO (-6675 -4225);
DISPLAY INVISIBLE (-6675 -4225);
FORCEPROP 0 LAST CDS_SEC 1
J 0
(-6675 -4225);
DISPLAY 1.021277 (-6675 -4225);
DISPLAY INVISIBLE (-6675 -4225);
FORCEADD UNIVERSAL_GND..1
(-4975 -6125);
FORCEPROP 3 LASTPIN (-4975 -6075) SIG_NAME GND\g
J 0
(-4965 -6065);
DISPLAY 0.659574 (-4965 -6065);
PAINT MONO (-4965 -6065);
DISPLAY INVISIBLE (-4965 -6065);
FORCEPROP 2 LAST CDS_LIB logical_power
J 0
(-4975 -6125);
PAINT MONO (-4975 -6125);
DISPLAY INVISIBLE (-4975 -6125);
FORCEPROP 1 LAST HDL_POWER GND
J 1
(-4950 -6200);
DISPLAY 0.872340 (-4950 -6200);
PAINT GREEN (-4950 -6200);
DISPLAY INVISIBLE (-4950 -6200);
FORCEPROP 1 LAST PATH I16
J 0
(-4900 -6125);
DISPLAY 0.872340 (-4900 -6125);
PAINT AQUA (-4900 -6125);
DISPLAY INVISIBLE (-4900 -6125);
FORCEPROP 2 LAST ROOM VR_CORE0_CTRL
J 0
(-5247 -6003);
DISPLAY INVISIBLE (-5247 -6003);
FORCEADD Q_CAP..1
(-4825 -4500);
FORCEPROP 1 LAST PART_NUMBER TMP_QCH2336K1B12
J 0
(-4775 -4650);
DISPLAY 0.617021 (-4775 -4650);
PAINT BLUE (-4775 -4650);
DISPLAY INVISIBLE (-4775 -4650);
FORCEPROP 1 LAST MATERIAL X7R
J 0
(-4775 -4550);
DISPLAY 0.617021 (-4775 -4550);
PAINT SKYBLUE (-4775 -4550);
FORCEPROP 1 LAST TOLERANCE 10%
J 0
(-4775 -4500);
DISPLAY 0.617021 (-4775 -4500);
PAINT SKYBLUE (-4775 -4500);
FORCEPROP 1 LAST VALUE 3300PF
J 0
(-4775 -4400);
DISPLAY 0.617021 (-4775 -4400);
PAINT SKYBLUE (-4775 -4400);
FORCEPROP 1 LAST VOLTAGE 50V
J 0
(-4775 -4450);
DISPLAY 0.617021 (-4775 -4450);
PAINT SKYBLUE (-4775 -4450);
FORCEPROP 1 LAST PACK_TYPE 0402
J 0
(-4775 -4600);
DISPLAY 0.617021 (-4775 -4600);
PAINT SKYBLUE (-4775 -4600);
FORCEPROP 1 LAST LOCATION PC230_P0_8
J 0
(-4775 -4350);
DISPLAY 0.617021 (-4775 -4350);
PAINT AQUA (-4775 -4350);
FORCEPROP 1 LASTPIN (-4825 -4400) $PN 1
J 0
(-4815 -4420);
DISPLAY 0.617021 (-4815 -4420);
PAINT MONO (-4815 -4420);
FORCEPROP 1 LASTPIN (-4825 -4600) $PN 2
J 0
(-4815 -4620);
DISPLAY 0.617021 (-4815 -4620);
PAINT MONO (-4815 -4620);
FORCEPROP 2 LAST CDS_LIB pure_quanta
J 0
(-4825 -4500);
DISPLAY INVISIBLE (-4825 -4500);
FORCEPROP 1 LAST PATH I17
J 0
(-4775 -4350);
DISPLAY 0.978723 (-4775 -4350);
PAINT WHITE (-4775 -4350);
DISPLAY INVISIBLE (-4775 -4350);
FORCEPROP 1 LAST LOCATION PC230_P0_8
J 0
(-4775 -4300);
DISPLAY 1.021277 (-4775 -4300);
PAINT AQUA (-4775 -4300);
DISPLAY INVISIBLE (-4775 -4300);
FORCEPROP 0 LAST $SEC 1
J 0
(-4775 -4300);
DISPLAY 0.680851 (-4775 -4300);
PAINT MONO (-4775 -4300);
DISPLAY INVISIBLE (-4775 -4300);
FORCEPROP 0 LAST CDS_SEC 1
J 0
(-4775 -4300);
DISPLAY 1.021277 (-4775 -4300);
DISPLAY INVISIBLE (-4775 -4300);
FORCEADD OFFPAGE..6
(-4100 -5650);
FORCEPROP 2 LAST $XR0 269 
J 0
(-4410 -5650);
DISPLAY 0.638298 (-4410 -5650);
PAINT MONO (-4410 -5650);
FORCEPROP 2 LAST CDS_LIB standard
J 0
(-4100 -5650);
DISPLAY INVISIBLE (-4100 -5650);
FORCEPROP 1 LAST OFFPAGE TRUE
J 0
(-3775 -5775);
DISPLAY 0.872340 (-3775 -5775);
PAINT GREEN (-3775 -5775);
DISPLAY INVISIBLE (-3775 -5775);
FORCEPROP 1 LAST COMMENT_BODY TRUE
J 0
(-4000 -5725);
DISPLAY 0.872340 (-4000 -5725);
PAINT GREEN (-4000 -5725);
DISPLAY INVISIBLE (-4000 -5725);
FORCEPROP 2 LAST PATH I18
J 0
(-4400 -5600);
DISPLAY 1.021277 (-4400 -5600);
DISPLAY INVISIBLE (-4400 -5600);
FORCEADD Q_RES..1
(-4375 -4950);
FORCEPROP 1 LAST PART_NUMBER CS-3302FB01
J 0
(-4475 -4900);
DISPLAY 0.617021 (-4475 -4900);
PAINT BLUE (-4475 -4900);
DISPLAY INVISIBLE (-4475 -4900);
FORCEPROP 1 LAST TOLERANCE 1%
J 0
(-4125 -4950);
DISPLAY 0.617021 (-4125 -4950);
PAINT SKYBLUE (-4125 -4950);
FORCEPROP 1 LAST MATERIAL CHIP
J 0
(-4475 -4800);
DISPLAY 0.617021 (-4475 -4800);
PAINT SKYBLUE (-4475 -4800);
FORCEPROP 1 LAST WATTAGE 1/16W
J 2
(-4150 -4850);
DISPLAY 0.617021 (-4150 -4850);
PAINT SKYBLUE (-4150 -4850);
FORCEPROP 1 LAST VALUE 3.3
J 2
(-4150 -4950);
DISPLAY 0.617021 (-4150 -4950);
PAINT SKYBLUE (-4150 -4950);
FORCEPROP 1 LAST PACK_TYPE 0402LF
J 0
(-4475 -4850);
DISPLAY 0.617021 (-4475 -4850);
PAINT SKYBLUE (-4475 -4850);
FORCEPROP 1 LAST LOCATION PR1772
J 0
(-4650 -4950);
DISPLAY 0.617021 (-4650 -4950);
PAINT AQUA (-4650 -4950);
FORCEPROP 1 LASTPIN (-4475 -4950) $PN 1
J 0
(-4463 -4938);
DISPLAY 0.617021 (-4463 -4938);
FORCEPROP 1 LASTPIN (-4275 -4950) $PN 2
J 0
(-4313 -4938);
DISPLAY 0.617021 (-4313 -4938);
FORCEPROP 2 LAST CDS_LIB pure_quanta
J 0
(-4375 -4950);
PAINT MONO (-4375 -4950);
DISPLAY INVISIBLE (-4375 -4950);
FORCEPROP 1 LAST PATH I19
J 0
(-4425 -4800);
DISPLAY 0.978723 (-4425 -4800);
PAINT WHITE (-4425 -4800);
DISPLAY INVISIBLE (-4425 -4800);
FORCEPROP 2 LAST $SEC 1
J 0
(-4425 -4750);
DISPLAY 0.680851 (-4425 -4750);
PAINT MONO (-4425 -4750);
DISPLAY INVISIBLE (-4425 -4750);
FORCEPROP 2 LAST CDS_SEC 1
J 0
(-4425 -4750);
DISPLAY 1.021277 (-4425 -4750);
DISPLAY INVISIBLE (-4425 -4750);
FORCEADD ISL99390FRZTR5935..1
(-5625 -5400);
FORCEPROP 1 LAST PART_NUMBER AL099390004
J 0
(-5925 -4600);
DISPLAY 0.617021 (-5925 -4600);
PAINT BLUE (-5925 -4600);
DISPLAY INVISIBLE (-5925 -4600);
FORCEPROP 2 LAST PART_TYPE SMLF
J 0
(-5925 -4400);
DISPLAY 0.638298 (-5925 -4400);
FORCEPROP 1 LAST MATERIAL IC
J 0
(-5925 -4675);
DISPLAY 0.617021 (-5925 -4675);
PAINT SKYBLUE (-5925 -4675);
FORCEPROP 2 LAST VALUE ISL99390FRZ-TR5935
J 0
(-5925 -4450);
DISPLAY 0.617021 (-5925 -4450);
PAINT SKYBLUE (-5925 -4450);
FORCEPROP 1 LAST LOCATION PU6_P0_8
J 0
(-5925 -4525);
DISPLAY 0.617021 (-5925 -4525);
PAINT AQUA (-5925 -4525);
FORCEPROP 2 LASTPIN (-5225 -5850) $PN 2
J 0
(-5215 -5840);
DISPLAY 0.617021 (-5215 -5840);
PAINT MONO (-5215 -5840);
FORCEPROP 2 LASTPIN (-5225 -5050) $PN 33
J 0
(-5215 -5040);
DISPLAY 0.617021 (-5215 -5040);
PAINT MONO (-5215 -5040);
FORCEPROP 2 LASTPIN (-6075 -5650) $PN 31
J 2
(-6085 -5640);
DISPLAY 0.617021 (-6085 -5640);
PAINT MONO (-6085 -5640);
FORCEPROP 2 LASTPIN (-6075 -5250) $PN 35
J 2
(-6085 -5240);
DISPLAY 0.617021 (-6085 -5240);
PAINT MONO (-6085 -5240);
FORCEPROP 2 LASTPIN (-5225 -5700) $PN 6
J 0
(-5215 -5690);
DISPLAY 0.617021 (-5215 -5690);
PAINT MONO (-5215 -5690);
FORCEPROP 2 LASTPIN (-5225 -5750) $PN 41
J 0
(-5215 -5740);
DISPLAY 0.617021 (-5215 -5740);
PAINT MONO (-5215 -5740);
FORCEPROP 2 LASTPIN (-6075 -5400) $PN 38
J 2
(-6085 -5390);
DISPLAY 0.617021 (-6085 -5390);
PAINT MONO (-6085 -5390);
FORCEPROP 2 LASTPIN (-6075 -5700) $PN 37
J 2
(-6085 -5690);
DISPLAY 0.617021 (-6085 -5690);
PAINT MONO (-6085 -5690);
FORCEPROP 2 LASTPIN (-5225 -5900) $PN 5
J 0
(-5215 -5890);
DISPLAY 0.617021 (-5215 -5890);
PAINT MONO (-5215 -5890);
FORCEPROP 2 LASTPIN (-5225 -5950) $PN 7_9-20_24
J 0
(-5215 -5940);
DISPLAY 0.617021 (-5215 -5940);
PAINT MONO (-5215 -5940);
FORCEPROP 2 LASTPIN (-5225 -6000) $PN 40
J 0
(-5215 -5990);
DISPLAY 0.617021 (-5215 -5990);
PAINT MONO (-5215 -5990);
FORCEPROP 2 LASTPIN (-5225 -5300) $PN 32
J 0
(-5215 -5290);
DISPLAY 0.617021 (-5215 -5290);
PAINT MONO (-5215 -5290);
FORCEPROP 2 LASTPIN (-6075 -4750) $PN 4
J 2
(-6085 -4740);
DISPLAY 0.617021 (-6085 -4740);
PAINT MONO (-6085 -4740);
FORCEPROP 2 LASTPIN (-6075 -6000) $PN 34
J 2
(-6085 -5990);
DISPLAY 0.617021 (-6085 -5990);
PAINT MONO (-6085 -5990);
FORCEPROP 2 LASTPIN (-6075 -5500) $PN 39
J 2
(-6085 -5490);
DISPLAY 0.617021 (-6085 -5490);
PAINT MONO (-6085 -5490);
FORCEPROP 2 LASTPIN (-5225 -5400) $PN 10_19
J 0
(-5215 -5390);
DISPLAY 0.617021 (-5215 -5390);
PAINT MONO (-5215 -5390);
FORCEPROP 2 LASTPIN (-6075 -5900) $PN 36
J 2
(-6085 -5890);
DISPLAY 0.617021 (-6085 -5890);
PAINT MONO (-6085 -5890);
FORCEPROP 2 LASTPIN (-6075 -5050) $PN 3
J 2
(-6085 -5040);
DISPLAY 0.617021 (-6085 -5040);
PAINT MONO (-6085 -5040);
FORCEPROP 2 LASTPIN (-5225 -4750) $PN 25_29
J 0
(-5215 -4740);
DISPLAY 0.617021 (-5215 -4740);
PAINT MONO (-5215 -4740);
FORCEPROP 2 LASTPIN (-5225 -4800) $PN 30
J 0
(-5215 -4790);
DISPLAY 0.617021 (-5215 -4790);
PAINT MONO (-5215 -4790);
FORCEPROP 2 LASTPIN (-5225 -5650) $PN 1
J 0
(-5215 -5640);
DISPLAY 0.617021 (-5215 -5640);
PAINT MONO (-5215 -5640);
FORCEPROP 1 LAST NEEDS_NO_SIZE TRUE
J 0
(-5625 -5400);
DISPLAY 0.723404 (-5625 -5400);
PAINT GREEN (-5625 -5400);
DISPLAY INVISIBLE (-5625 -5400);
FORCEPROP 1 LAST CDS_LMAN_SYM_OUTLINE -300,700,250,-650
J 0
(-5625 -5400);
DISPLAY 0.468085 (-5625 -5400);
PAINT GREEN (-5625 -5400);
DISPLAY INVISIBLE (-5625 -5400);
FORCEPROP 2 LAST CDS_LIB pure_quanta
J 0
(-5625 -5400);
DISPLAY INVISIBLE (-5625 -5400);
FORCEPROP 1 LAST PATH I2
J 0
(-5625 -5400);
DISPLAY 0.723404 (-5625 -5400);
PAINT GREEN (-5625 -5400);
DISPLAY INVISIBLE (-5625 -5400);
FORCEPROP 2 LAST $SEC 1
J 0
(-5925 -4475);
DISPLAY 0.680851 (-5925 -4475);
PAINT MONO (-5925 -4475);
DISPLAY INVISIBLE (-5925 -4475);
FORCEPROP 2 LAST CDS_SEC 1
J 0
(-5925 -4475);
DISPLAY 1.021277 (-5925 -4475);
DISPLAY INVISIBLE (-5925 -4475);
FORCEADD Q_CAP..1
(-4425 -4500);
FORCEPROP 1 LAST PART_NUMBER CH5103KEB01
J 0
(-4375 -4650);
DISPLAY 0.617021 (-4375 -4650);
PAINT BLUE (-4375 -4650);
DISPLAY INVISIBLE (-4375 -4650);
FORCEPROP 1 LAST MATERIAL X6S
J 0
(-4375 -4550);
DISPLAY 0.617021 (-4375 -4550);
PAINT SKYBLUE (-4375 -4550);
FORCEPROP 1 LAST TOLERANCE 10%
J 0
(-4375 -4500);
DISPLAY 0.617021 (-4375 -4500);
PAINT SKYBLUE (-4375 -4500);
FORCEPROP 1 LAST VALUE 1UF
J 0
(-4375 -4400);
DISPLAY 0.617021 (-4375 -4400);
PAINT SKYBLUE (-4375 -4400);
FORCEPROP 1 LAST VOLTAGE 16V
J 0
(-4375 -4450);
DISPLAY 0.617021 (-4375 -4450);
PAINT SKYBLUE (-4375 -4450);
FORCEPROP 1 LAST PACK_TYPE C0402
J 0
(-4375 -4600);
DISPLAY 0.617021 (-4375 -4600);
PAINT SKYBLUE (-4375 -4600);
FORCEPROP 1 LAST LOCATION PC232_P0_8
J 0
(-4375 -4350);
DISPLAY 0.617021 (-4375 -4350);
PAINT AQUA (-4375 -4350);
FORCEPROP 1 LASTPIN (-4425 -4400) $PN 1
J 0
(-4415 -4420);
DISPLAY 0.617021 (-4415 -4420);
PAINT MONO (-4415 -4420);
FORCEPROP 1 LASTPIN (-4425 -4600) $PN 2
J 0
(-4415 -4620);
DISPLAY 0.617021 (-4415 -4620);
PAINT MONO (-4415 -4620);
FORCEPROP 2 LAST CDS_LIB pure_quanta
J 0
(-4425 -4500);
DISPLAY INVISIBLE (-4425 -4500);
FORCEPROP 1 LAST PATH I20
J 0
(-4375 -4350);
DISPLAY 0.978723 (-4375 -4350);
PAINT WHITE (-4375 -4350);
DISPLAY INVISIBLE (-4375 -4350);
FORCEPROP 1 LAST LOCATION PC232_P0_8
J 0
(-4375 -4300);
DISPLAY 1.021277 (-4375 -4300);
PAINT AQUA (-4375 -4300);
DISPLAY INVISIBLE (-4375 -4300);
FORCEPROP 0 LAST $SEC 1
J 0
(-4375 -4300);
DISPLAY 0.680851 (-4375 -4300);
PAINT MONO (-4375 -4300);
DISPLAY INVISIBLE (-4375 -4300);
FORCEPROP 0 LAST CDS_SEC 1
J 0
(-4375 -4300);
DISPLAY 1.021277 (-4375 -4300);
DISPLAY INVISIBLE (-4375 -4300);
FORCEADD Q_CAP..1
(-4025 -4500);
FORCEPROP 1 LAST PART_NUMBER CH6223MEA01
J 0
(-3975 -4650);
DISPLAY 0.617021 (-3975 -4650);
PAINT BLUE (-3975 -4650);
DISPLAY INVISIBLE (-3975 -4650);
FORCEPROP 1 LAST MATERIAL X6S
J 0
(-3975 -4550);
DISPLAY 0.617021 (-3975 -4550);
PAINT SKYBLUE (-3975 -4550);
FORCEPROP 1 LAST TOLERANCE 20%
J 0
(-3975 -4500);
DISPLAY 0.617021 (-3975 -4500);
PAINT SKYBLUE (-3975 -4500);
FORCEPROP 1 LAST VALUE 22UF
J 0
(-3975 -4400);
DISPLAY 0.617021 (-3975 -4400);
PAINT SKYBLUE (-3975 -4400);
FORCEPROP 1 LAST VOLTAGE 16V
J 0
(-3975 -4450);
DISPLAY 0.617021 (-3975 -4450);
PAINT SKYBLUE (-3975 -4450);
FORCEPROP 1 LAST PACK_TYPE C0805
J 0
(-3975 -4600);
DISPLAY 0.617021 (-3975 -4600);
PAINT SKYBLUE (-3975 -4600);
FORCEPROP 1 LAST LOCATION PC236_P0_8
J 0
(-3975 -4350);
DISPLAY 0.617021 (-3975 -4350);
PAINT AQUA (-3975 -4350);
FORCEPROP 1 LASTPIN (-4025 -4400) $PN 1
J 0
(-4015 -4420);
DISPLAY 0.617021 (-4015 -4420);
PAINT MONO (-4015 -4420);
FORCEPROP 1 LASTPIN (-4025 -4600) $PN 2
J 0
(-4015 -4620);
DISPLAY 0.617021 (-4015 -4620);
PAINT MONO (-4015 -4620);
FORCEPROP 2 LAST CDS_LIB pure_quanta
J 0
(-4025 -4500);
DISPLAY INVISIBLE (-4025 -4500);
FORCEPROP 1 LAST PATH I21
J 0
(-3975 -4350);
DISPLAY 0.978723 (-3975 -4350);
PAINT WHITE (-3975 -4350);
DISPLAY INVISIBLE (-3975 -4350);
FORCEPROP 1 LAST LOCATION PC236_P0_8
J 0
(-3975 -4300);
DISPLAY 1.021277 (-3975 -4300);
PAINT AQUA (-3975 -4300);
DISPLAY INVISIBLE (-3975 -4300);
FORCEPROP 0 LAST $SEC 1
J 0
(-3975 -4300);
DISPLAY 0.680851 (-3975 -4300);
PAINT MONO (-3975 -4300);
DISPLAY INVISIBLE (-3975 -4300);
FORCEPROP 0 LAST CDS_SEC 1
J 0
(-3975 -4300);
DISPLAY 1.021277 (-3975 -4300);
DISPLAY INVISIBLE (-3975 -4300);
FORCEADD UNIVERSAL_GND..1
(-7525 -3300);
FORCEPROP 3 LASTPIN (-7525 -3250) SIG_NAME GND\g
J 0
(-7515 -3240);
DISPLAY 0.659574 (-7515 -3240);
PAINT MONO (-7515 -3240);
DISPLAY INVISIBLE (-7515 -3240);
FORCEPROP 2 LAST CDS_LIB logical_power
J 0
(-7525 -3300);
PAINT MONO (-7525 -3300);
DISPLAY INVISIBLE (-7525 -3300);
FORCEPROP 1 LAST HDL_POWER GND
J 1
(-7500 -3375);
DISPLAY 0.872340 (-7500 -3375);
PAINT GREEN (-7500 -3375);
DISPLAY INVISIBLE (-7500 -3375);
FORCEPROP 1 LAST PATH I22
J 0
(-7450 -3300);
DISPLAY 0.872340 (-7450 -3300);
PAINT AQUA (-7450 -3300);
DISPLAY INVISIBLE (-7450 -3300);
FORCEPROP 2 LAST ROOM VR_CORE0_CTRL
J 0
(-7797 -3178);
DISPLAY INVISIBLE (-7797 -3178);
FORCEADD Q_RES..2
R 2
(-7525 -3075);
FORCEPROP 1 LAST PART_NUMBER CS28872FB01
J 2
(-7565 -3200);
DISPLAY 0.617021 (-7565 -3200);
PAINT BLUE (-7565 -3200);
DISPLAY INVISIBLE (-7565 -3200);
FORCEPROP 1 LAST WATTAGE 1/16W
J 2
(-7565 -3100);
DISPLAY 0.617021 (-7565 -3100);
PAINT SKYBLUE (-7565 -3100);
FORCEPROP 1 LAST MATERIAL EMPTY
J 2
(-7565 -3150);
DISPLAY 0.617021 (-7565 -3150);
PAINT RED (-7565 -3150);
FORCEPROP 1 LAST TOLERANCE 1%
J 2
(-7570 -3050);
DISPLAY 0.617021 (-7570 -3050);
PAINT SKYBLUE (-7570 -3050);
FORCEPROP 1 LAST VALUE 8.87K
J 2
(-7570 -3000);
DISPLAY 0.617021 (-7570 -3000);
PAINT SKYBLUE (-7570 -3000);
FORCEPROP 1 LAST PACK_TYPE 0402LF
J 2
(-7565 -3250);
DISPLAY 0.617021 (-7565 -3250);
PAINT SKYBLUE (-7565 -3250);
FORCEPROP 1 LAST LOCATION PR133
J 2
(-7570 -2950);
DISPLAY 0.617021 (-7570 -2950);
PAINT AQUA (-7570 -2950);
FORCEPROP 1 LASTPIN (-7525 -2975) $PN 1
J 2
(-7530 -3013);
DISPLAY 0.617021 (-7530 -3013);
PAINT MONO (-7530 -3013);
FORCEPROP 1 LASTPIN (-7525 -3175) $PN 2
J 2
(-7530 -3165);
DISPLAY 0.617021 (-7530 -3165);
PAINT MONO (-7530 -3165);
FORCEPROP 2 LAST CDS_LIB pure_quanta
J 2
(-7525 -3075);
DISPLAY INVISIBLE (-7525 -3075);
FORCEPROP 1 LAST PATH I23
J 2
(-7575 -2900);
DISPLAY 0.978723 (-7575 -2900);
PAINT WHITE (-7575 -2900);
DISPLAY INVISIBLE (-7575 -2900);
FORCEPROP 0 LAST $SEC 1
J 0
(-7550 -2900);
DISPLAY 0.680851 (-7550 -2900);
PAINT MONO (-7550 -2900);
DISPLAY INVISIBLE (-7550 -2900);
FORCEPROP 0 LAST CDS_SEC 1
J 0
(-7550 -2900);
DISPLAY 1.021277 (-7550 -2900);
DISPLAY INVISIBLE (-7550 -2900);
FORCEADD OFFPAGE..5
(-7050 -3075);
FORCEPROP 2 LAST $XR4 266 
J 0
(-7335 -2967);
DISPLAY 0.638298 (-7335 -2967);
PAINT MONO (-7335 -2967);
FORCEPROP 2 LAST $XR3 270 
J 0
(-7335 -3003);
DISPLAY 0.638298 (-7335 -3003);
PAINT MONO (-7335 -3003);
FORCEPROP 2 LAST $XR2 269 
J 0
(-7335 -3039);
DISPLAY 0.638298 (-7335 -3039);
PAINT MONO (-7335 -3039);
FORCEPROP 2 LAST $XR1 268 
J 0
(-7335 -3111);
DISPLAY 0.638298 (-7335 -3111);
PAINT MONO (-7335 -3111);
FORCEPROP 2 LAST $XR0 267 
J 0
(-7335 -3075);
DISPLAY 0.638298 (-7335 -3075);
PAINT MONO (-7335 -3075);
FORCEPROP 2 LAST CDS_LIB standard
J 0
(-7050 -3075);
DISPLAY INVISIBLE (-7050 -3075);
FORCEPROP 1 LAST OFFPAGE TRUE
J 0
(-6725 -3200);
DISPLAY 0.872340 (-6725 -3200);
PAINT GREEN (-6725 -3200);
DISPLAY INVISIBLE (-6725 -3200);
FORCEPROP 1 LAST COMMENT_BODY TRUE
J 0
(-6950 -3150);
DISPLAY 0.872340 (-6950 -3150);
PAINT GREEN (-6950 -3150);
DISPLAY INVISIBLE (-6950 -3150);
FORCEPROP 2 LAST PATH I24
J 0
(-7325 -2925);
DISPLAY 1.021277 (-7325 -2925);
DISPLAY INVISIBLE (-7325 -2925);
FORCEADD OFFPAGE..1
(-7050 -3175);
FORCEPROP 2 LAST $XR0 266 
J 0
(-7302 -3175);
DISPLAY 0.638298 (-7302 -3175);
PAINT MONO (-7302 -3175);
FORCEPROP 2 LAST CDS_LIB standard
J 0
(-7050 -3175);
DISPLAY INVISIBLE (-7050 -3175);
FORCEPROP 1 LAST OFFPAGE TRUE
J 0
(-6725 -3300);
DISPLAY 0.872340 (-6725 -3300);
PAINT GREEN (-6725 -3300);
DISPLAY INVISIBLE (-6725 -3300);
FORCEPROP 1 LAST COMMENT_BODY TRUE
J 0
(-6925 -3275);
DISPLAY 0.872340 (-6925 -3275);
PAINT GREEN (-6925 -3275);
DISPLAY INVISIBLE (-6925 -3275);
FORCEPROP 2 LAST PATH I25
J 0
(-7300 -3125);
DISPLAY 1.021277 (-7300 -3125);
DISPLAY INVISIBLE (-7300 -3125);
FORCEADD UNIVERSAL_GND..1
(-7625 -2850);
FORCEPROP 3 LASTPIN (-7625 -2800) SIG_NAME GND\g
J 0
(-7615 -2790);
DISPLAY 0.659574 (-7615 -2790);
PAINT MONO (-7615 -2790);
DISPLAY INVISIBLE (-7615 -2790);
FORCEPROP 2 LAST CDS_LIB logical_power
J 0
(-7625 -2850);
PAINT MONO (-7625 -2850);
DISPLAY INVISIBLE (-7625 -2850);
FORCEPROP 1 LAST HDL_POWER GND
J 1
(-7600 -2925);
DISPLAY 0.872340 (-7600 -2925);
PAINT GREEN (-7600 -2925);
DISPLAY INVISIBLE (-7600 -2925);
FORCEPROP 1 LAST PATH I26
J 0
(-7550 -2850);
DISPLAY 0.872340 (-7550 -2850);
PAINT AQUA (-7550 -2850);
DISPLAY INVISIBLE (-7550 -2850);
FORCEADD OFFPAGE..1
(-7050 -2675);
FORCEPROP 2 LAST $XR6 272 
J 0
(-8022 -2675);
DISPLAY 0.638298 (-8022 -2675);
PAINT MONO (-8022 -2675);
FORCEPROP 2 LAST $XR5 271 
J 0
(-7902 -2675);
DISPLAY 0.638298 (-7902 -2675);
PAINT MONO (-7902 -2675);
FORCEPROP 2 LAST $XR4 270 
J 0
(-7782 -2675);
DISPLAY 0.638298 (-7782 -2675);
PAINT MONO (-7782 -2675);
FORCEPROP 2 LAST $XR3 269 
J 0
(-7662 -2675);
DISPLAY 0.638298 (-7662 -2675);
PAINT MONO (-7662 -2675);
FORCEPROP 2 LAST $XR2 268 
J 0
(-7542 -2675);
DISPLAY 0.638298 (-7542 -2675);
PAINT MONO (-7542 -2675);
FORCEPROP 2 LAST $XR1 267 
J 0
(-7422 -2675);
DISPLAY 0.638298 (-7422 -2675);
PAINT MONO (-7422 -2675);
FORCEPROP 2 LAST $XR0 266 
J 0
(-7302 -2675);
DISPLAY 0.638298 (-7302 -2675);
PAINT MONO (-7302 -2675);
FORCEPROP 2 LAST CDS_LIB standard
J 0
(-7050 -2675);
DISPLAY INVISIBLE (-7050 -2675);
FORCEPROP 1 LAST OFFPAGE TRUE
J 0
(-6725 -2800);
DISPLAY 0.872340 (-6725 -2800);
PAINT GREEN (-6725 -2800);
DISPLAY INVISIBLE (-6725 -2800);
FORCEPROP 1 LAST COMMENT_BODY TRUE
J 0
(-6925 -2775);
DISPLAY 0.872340 (-6925 -2775);
PAINT GREEN (-6925 -2775);
DISPLAY INVISIBLE (-6925 -2775);
FORCEPROP 2 LAST PATH I27
J 0
(-7300 -2625);
DISPLAY 1.021277 (-7300 -2625);
DISPLAY INVISIBLE (-7300 -2625);
FORCEADD OFFPAGE..5
(-7050 -2575);
FORCEPROP 2 LAST $XR0 266 
J 0
(-7335 -2575);
DISPLAY 0.638298 (-7335 -2575);
PAINT MONO (-7335 -2575);
FORCEPROP 2 LAST CDS_LIB standard
J 0
(-7050 -2575);
DISPLAY INVISIBLE (-7050 -2575);
FORCEPROP 1 LAST OFFPAGE TRUE
J 0
(-6725 -2700);
DISPLAY 0.872340 (-6725 -2700);
PAINT GREEN (-6725 -2700);
DISPLAY INVISIBLE (-6725 -2700);
FORCEPROP 1 LAST COMMENT_BODY TRUE
J 0
(-6950 -2650);
DISPLAY 0.872340 (-6950 -2650);
PAINT GREEN (-6950 -2650);
DISPLAY INVISIBLE (-6950 -2650);
FORCEPROP 2 LAST PATH I28
J 0
(-7325 -2525);
DISPLAY 1.021277 (-7325 -2525);
DISPLAY INVISIBLE (-7325 -2525);
FORCEADD Q_CAP..2
(-6950 -2775);
FORCEPROP 1 LAST PART_NUMBER CH4104K1B00
J 1
(-6650 -2750);
DISPLAY 0.617021 (-6650 -2750);
PAINT BLUE (-6650 -2750);
DISPLAY INVISIBLE (-6650 -2750);
FORCEPROP 1 LAST VALUE 0.1UF
J 2
(-6650 -2775);
DISPLAY 0.617021 (-6650 -2775);
PAINT SKYBLUE (-6650 -2775);
FORCEPROP 1 LAST MATERIAL X7R
J 0
(-6500 -2750);
DISPLAY 0.617021 (-6500 -2750);
PAINT SKYBLUE (-6500 -2750);
FORCEPROP 1 LAST TOLERANCE 10%
J 2
(-6325 -2750);
DISPLAY 0.617021 (-6325 -2750);
PAINT SKYBLUE (-6325 -2750);
FORCEPROP 1 LAST PACK_TYPE 0402
J 1
(-6425 -2775);
DISPLAY 0.617021 (-6425 -2775);
PAINT SKYBLUE (-6425 -2775);
FORCEPROP 1 LAST VOLTAGE 25V
J 0
(-6625 -2775);
DISPLAY 0.617021 (-6625 -2775);
PAINT SKYBLUE (-6625 -2775);
FORCEPROP 1 LAST LOCATION PC1345
J 1
(-7150 -2775);
DISPLAY 0.617021 (-7150 -2775);
PAINT AQUA (-7150 -2775);
FORCEPROP 1 LASTPIN (-7050 -2775) $PN 1
J 0
(-7060 -2760);
DISPLAY 0.617021 (-7060 -2760);
FORCEPROP 1 LASTPIN (-6850 -2775) $PN 2
J 0
(-6865 -2760);
DISPLAY 0.617021 (-6865 -2760);
FORCEPROP 2 LAST CDS_LIB pure_quanta
J 0
(-6950 -2775);
PAINT MONO (-6950 -2775);
DISPLAY INVISIBLE (-6950 -2775);
FORCEPROP 1 LAST PATH I29
J 0
(-6950 -2575);
DISPLAY 0.978723 (-6950 -2575);
PAINT WHITE (-6950 -2575);
DISPLAY INVISIBLE (-6950 -2575);
FORCEPROP 2 LAST $SEC 1
J 0
(-6950 -2525);
DISPLAY 0.680851 (-6950 -2525);
PAINT MONO (-6950 -2525);
DISPLAY INVISIBLE (-6950 -2525);
FORCEPROP 2 LAST CDS_SEC 1
J 0
(-6950 -2525);
DISPLAY 1.021277 (-6950 -2525);
DISPLAY INVISIBLE (-6950 -2525);
FORCEADD UNIVERSAL_GND..1
(-7650 -5675);
FORCEPROP 3 LASTPIN (-7650 -5625) SIG_NAME GND\g
J 0
(-7640 -5615);
DISPLAY 0.659574 (-7640 -5615);
PAINT MONO (-7640 -5615);
DISPLAY INVISIBLE (-7640 -5615);
FORCEPROP 2 LAST CDS_LIB logical_power
J 0
(-7650 -5675);
PAINT MONO (-7650 -5675);
DISPLAY INVISIBLE (-7650 -5675);
FORCEPROP 1 LAST HDL_POWER GND
J 1
(-7625 -5750);
DISPLAY 0.872340 (-7625 -5750);
PAINT GREEN (-7625 -5750);
DISPLAY INVISIBLE (-7625 -5750);
FORCEPROP 1 LAST PATH I3
J 0
(-7575 -5675);
DISPLAY 0.872340 (-7575 -5675);
PAINT AQUA (-7575 -5675);
DISPLAY INVISIBLE (-7575 -5675);
FORCEADD UNIVERSAL_GND..1
(-7125 -2325);
FORCEPROP 3 LASTPIN (-7125 -2275) SIG_NAME GND\g
J 0
(-7115 -2265);
DISPLAY 0.659574 (-7115 -2265);
PAINT MONO (-7115 -2265);
DISPLAY INVISIBLE (-7115 -2265);
FORCEPROP 2 LAST CDS_LIB logical_power
J 0
(-7125 -2325);
PAINT MONO (-7125 -2325);
DISPLAY INVISIBLE (-7125 -2325);
FORCEPROP 1 LAST HDL_POWER GND
J 1
(-7100 -2400);
DISPLAY 0.872340 (-7100 -2400);
PAINT GREEN (-7100 -2400);
DISPLAY INVISIBLE (-7100 -2400);
FORCEPROP 1 LAST PATH I30
J 0
(-7050 -2325);
DISPLAY 0.872340 (-7050 -2325);
PAINT AQUA (-7050 -2325);
DISPLAY INVISIBLE (-7050 -2325);
FORCEPROP 2 LAST ROOM VR_CORE0_CTRL
J 0
(-7397 -2203);
DISPLAY INVISIBLE (-7397 -2203);
FORCEADD Q_CAP..1
(-7125 -2075);
FORCEPROP 1 LAST PART_NUMBER CH5222KEB01
J 0
(-7075 -2250);
DISPLAY 0.617021 (-7075 -2250);
PAINT BLUE (-7075 -2250);
DISPLAY INVISIBLE (-7075 -2250);
FORCEPROP 1 LAST MATERIAL X6S
J 0
(-7075 -2150);
DISPLAY 0.617021 (-7075 -2150);
PAINT SKYBLUE (-7075 -2150);
FORCEPROP 1 LAST TOLERANCE 10%
J 0
(-7075 -2100);
DISPLAY 0.617021 (-7075 -2100);
PAINT SKYBLUE (-7075 -2100);
FORCEPROP 1 LAST VALUE 2.2UF
J 0
(-7075 -2000);
DISPLAY 0.617021 (-7075 -2000);
PAINT SKYBLUE (-7075 -2000);
FORCEPROP 1 LAST VOLTAGE 10V
J 0
(-7075 -2050);
DISPLAY 0.617021 (-7075 -2050);
PAINT SKYBLUE (-7075 -2050);
FORCEPROP 1 LAST PACK_TYPE C0402
J 0
(-7075 -2200);
DISPLAY 0.617021 (-7075 -2200);
PAINT SKYBLUE (-7075 -2200);
FORCEPROP 1 LAST LOCATION PC227
J 0
(-7075 -1950);
DISPLAY 0.617021 (-7075 -1950);
PAINT AQUA (-7075 -1950);
FORCEPROP 1 LASTPIN (-7125 -1975) $PN 1
J 0
(-7115 -1995);
DISPLAY 0.617021 (-7115 -1995);
PAINT MONO (-7115 -1995);
FORCEPROP 1 LASTPIN (-7125 -2175) $PN 2
J 0
(-7115 -2195);
DISPLAY 0.617021 (-7115 -2195);
PAINT MONO (-7115 -2195);
FORCEPROP 2 LAST CDS_LIB pure_quanta
J 0
(-7125 -2075);
DISPLAY INVISIBLE (-7125 -2075);
FORCEPROP 1 LAST PATH I31
J 0
(-7075 -1925);
DISPLAY 0.978723 (-7075 -1925);
PAINT WHITE (-7075 -1925);
DISPLAY INVISIBLE (-7075 -1925);
FORCEPROP 1 LAST LOCATION PC227
J 0
(-7075 -1900);
DISPLAY 1.021277 (-7075 -1900);
PAINT AQUA (-7075 -1900);
DISPLAY INVISIBLE (-7075 -1900);
FORCEPROP 0 LAST $SEC 1
J 0
(-7075 -1900);
DISPLAY 0.680851 (-7075 -1900);
PAINT MONO (-7075 -1900);
DISPLAY INVISIBLE (-7075 -1900);
FORCEPROP 0 LAST CDS_SEC 1
J 0
(-7075 -1900);
DISPLAY 1.021277 (-7075 -1900);
DISPLAY INVISIBLE (-7075 -1900);
FORCEADD ISL99390FRZTR5935..1
(-5600 -2575);
FORCEPROP 1 LAST PART_NUMBER AL099390004
J 0
(-5900 -1775);
DISPLAY 0.617021 (-5900 -1775);
PAINT BLUE (-5900 -1775);
DISPLAY INVISIBLE (-5900 -1775);
FORCEPROP 2 LAST PART_TYPE SMLF
J 0
(-5900 -1575);
DISPLAY 0.638298 (-5900 -1575);
FORCEPROP 2 LAST VALUE ISL99390FRZ-TR5935
J 0
(-5900 -1625);
DISPLAY 0.617021 (-5900 -1625);
PAINT SKYBLUE (-5900 -1625);
FORCEPROP 1 LAST MATERIAL IC
J 0
(-5900 -1850);
DISPLAY 0.617021 (-5900 -1850);
PAINT SKYBLUE (-5900 -1850);
FORCEPROP 1 LAST LOCATION PU7_P0_7
J 0
(-5900 -1700);
DISPLAY 0.617021 (-5900 -1700);
PAINT AQUA (-5900 -1700);
FORCEPROP 2 LASTPIN (-5200 -3025) $PN 2
J 0
(-5190 -3015);
DISPLAY 0.617021 (-5190 -3015);
PAINT MONO (-5190 -3015);
FORCEPROP 2 LASTPIN (-5200 -2225) $PN 33
J 0
(-5190 -2215);
DISPLAY 0.617021 (-5190 -2215);
PAINT MONO (-5190 -2215);
FORCEPROP 2 LASTPIN (-6050 -2825) $PN 31
J 2
(-6060 -2815);
DISPLAY 0.617021 (-6060 -2815);
PAINT MONO (-6060 -2815);
FORCEPROP 2 LASTPIN (-6050 -2425) $PN 35
J 2
(-6060 -2415);
DISPLAY 0.617021 (-6060 -2415);
PAINT MONO (-6060 -2415);
FORCEPROP 2 LASTPIN (-5200 -2875) $PN 6
J 0
(-5190 -2865);
DISPLAY 0.617021 (-5190 -2865);
PAINT MONO (-5190 -2865);
FORCEPROP 2 LASTPIN (-5200 -2925) $PN 41
J 0
(-5190 -2915);
DISPLAY 0.617021 (-5190 -2915);
PAINT MONO (-5190 -2915);
FORCEPROP 2 LASTPIN (-6050 -2575) $PN 38
J 2
(-6060 -2565);
DISPLAY 0.617021 (-6060 -2565);
PAINT MONO (-6060 -2565);
FORCEPROP 2 LASTPIN (-6050 -2875) $PN 37
J 2
(-6060 -2865);
DISPLAY 0.617021 (-6060 -2865);
PAINT MONO (-6060 -2865);
FORCEPROP 2 LASTPIN (-5200 -3075) $PN 5
J 0
(-5190 -3065);
DISPLAY 0.617021 (-5190 -3065);
PAINT MONO (-5190 -3065);
FORCEPROP 2 LASTPIN (-5200 -3125) $PN 7_9-20_24
J 0
(-5190 -3115);
DISPLAY 0.617021 (-5190 -3115);
PAINT MONO (-5190 -3115);
FORCEPROP 2 LASTPIN (-5200 -3175) $PN 40
J 0
(-5190 -3165);
DISPLAY 0.617021 (-5190 -3165);
PAINT MONO (-5190 -3165);
FORCEPROP 2 LASTPIN (-5200 -2475) $PN 32
J 0
(-5190 -2465);
DISPLAY 0.617021 (-5190 -2465);
PAINT MONO (-5190 -2465);
FORCEPROP 2 LASTPIN (-6050 -1925) $PN 4
J 2
(-6060 -1915);
DISPLAY 0.617021 (-6060 -1915);
PAINT MONO (-6060 -1915);
FORCEPROP 2 LASTPIN (-6050 -3175) $PN 34
J 2
(-6060 -3165);
DISPLAY 0.617021 (-6060 -3165);
PAINT MONO (-6060 -3165);
FORCEPROP 2 LASTPIN (-6050 -2675) $PN 39
J 2
(-6060 -2665);
DISPLAY 0.617021 (-6060 -2665);
PAINT MONO (-6060 -2665);
FORCEPROP 2 LASTPIN (-5200 -2575) $PN 10_19
J 0
(-5190 -2565);
DISPLAY 0.617021 (-5190 -2565);
PAINT MONO (-5190 -2565);
FORCEPROP 2 LASTPIN (-6050 -3075) $PN 36
J 2
(-6060 -3065);
DISPLAY 0.617021 (-6060 -3065);
PAINT MONO (-6060 -3065);
FORCEPROP 2 LASTPIN (-6050 -2225) $PN 3
J 2
(-6060 -2215);
DISPLAY 0.617021 (-6060 -2215);
PAINT MONO (-6060 -2215);
FORCEPROP 2 LASTPIN (-5200 -1925) $PN 25_29
J 0
(-5190 -1915);
DISPLAY 0.617021 (-5190 -1915);
PAINT MONO (-5190 -1915);
FORCEPROP 2 LASTPIN (-5200 -1975) $PN 30
J 0
(-5190 -1965);
DISPLAY 0.617021 (-5190 -1965);
PAINT MONO (-5190 -1965);
FORCEPROP 2 LASTPIN (-5200 -2825) $PN 1
J 0
(-5190 -2815);
DISPLAY 0.617021 (-5190 -2815);
PAINT MONO (-5190 -2815);
FORCEPROP 1 LAST NEEDS_NO_SIZE TRUE
J 0
(-5600 -2575);
DISPLAY 0.723404 (-5600 -2575);
PAINT GREEN (-5600 -2575);
DISPLAY INVISIBLE (-5600 -2575);
FORCEPROP 1 LAST CDS_LMAN_SYM_OUTLINE -300,700,250,-650
J 0
(-5600 -2575);
DISPLAY 0.468085 (-5600 -2575);
PAINT GREEN (-5600 -2575);
DISPLAY INVISIBLE (-5600 -2575);
FORCEPROP 2 LAST CDS_LIB pure_quanta
J 0
(-5600 -2575);
DISPLAY INVISIBLE (-5600 -2575);
FORCEPROP 1 LAST PATH I32
J 0
(-5600 -2575);
DISPLAY 0.723404 (-5600 -2575);
PAINT GREEN (-5600 -2575);
DISPLAY INVISIBLE (-5600 -2575);
FORCEPROP 2 LAST $SEC 1
J 0
(-5900 -1650);
DISPLAY 0.680851 (-5900 -1650);
PAINT MONO (-5900 -1650);
DISPLAY INVISIBLE (-5900 -1650);
FORCEPROP 2 LAST CDS_SEC 1
J 0
(-5900 -1650);
DISPLAY 1.021277 (-5900 -1650);
DISPLAY INVISIBLE (-5900 -1650);
FORCEADD Q_RES..2
(-7125 -1575);
FORCEPROP 1 LAST PART_NUMBER CS-2202FB01
J 0
(-7085 -1700);
DISPLAY 0.617021 (-7085 -1700);
PAINT BLUE (-7085 -1700);
DISPLAY INVISIBLE (-7085 -1700);
FORCEPROP 1 LAST WATTAGE 1/16W
J 0
(-7085 -1600);
DISPLAY 0.617021 (-7085 -1600);
PAINT SKYBLUE (-7085 -1600);
FORCEPROP 1 LAST MATERIAL CHIP
J 0
(-7085 -1650);
DISPLAY 0.617021 (-7085 -1650);
PAINT SKYBLUE (-7085 -1650);
FORCEPROP 1 LAST TOLERANCE 1%
J 0
(-7080 -1550);
DISPLAY 0.617021 (-7080 -1550);
PAINT SKYBLUE (-7080 -1550);
FORCEPROP 1 LAST VALUE 2.2
J 0
(-7080 -1500);
DISPLAY 0.617021 (-7080 -1500);
PAINT SKYBLUE (-7080 -1500);
FORCEPROP 1 LAST PACK_TYPE 0402LF
J 0
(-7085 -1750);
DISPLAY 0.617021 (-7085 -1750);
PAINT SKYBLUE (-7085 -1750);
FORCEPROP 1 LAST LOCATION PR135
J 0
(-7080 -1450);
DISPLAY 0.617021 (-7080 -1450);
PAINT AQUA (-7080 -1450);
FORCEPROP 1 LASTPIN (-7125 -1475) $PN 1
J 0
(-7120 -1513);
DISPLAY 0.617021 (-7120 -1513);
PAINT MONO (-7120 -1513);
FORCEPROP 1 LASTPIN (-7125 -1675) $PN 2
J 0
(-7120 -1665);
DISPLAY 0.617021 (-7120 -1665);
PAINT MONO (-7120 -1665);
FORCEPROP 2 LAST CDS_LIB pure_quanta
J 0
(-7125 -1575);
DISPLAY INVISIBLE (-7125 -1575);
FORCEPROP 1 LAST PATH I33
J 0
(-7075 -1400);
DISPLAY 0.978723 (-7075 -1400);
PAINT WHITE (-7075 -1400);
DISPLAY INVISIBLE (-7075 -1400);
FORCEPROP 1 LAST LOCATION PR135
J 0
(-7075 -1400);
DISPLAY 1.021277 (-7075 -1400);
PAINT AQUA (-7075 -1400);
DISPLAY INVISIBLE (-7075 -1400);
FORCEPROP 0 LAST $SEC 1
J 0
(-7075 -1400);
DISPLAY 0.680851 (-7075 -1400);
PAINT MONO (-7075 -1400);
DISPLAY INVISIBLE (-7075 -1400);
FORCEPROP 0 LAST CDS_SEC 1
J 0
(-7075 -1400);
DISPLAY 1.021277 (-7075 -1400);
DISPLAY INVISIBLE (-7075 -1400);
FORCEADD VCC15..1
(-7125 -1250);
FORCEPROP 3 LASTPIN (-7125 -1300) SIG_NAME PVCCIN_CPU0_PVCC\g
J 0
(-7115 -1290);
DISPLAY 0.659574 (-7115 -1290);
PAINT MONO (-7115 -1290);
DISPLAY INVISIBLE (-7115 -1290);
FORCEPROP 1 LAST HDL_POWER PVCCIN_CPU0_PVCC
J 1
(-7125 -1200);
DISPLAY 0.617021 (-7125 -1200);
PAINT GREEN (-7125 -1200);
FORCEPROP 2 LAST CDS_LIB logical_power
J 0
(-7125 -1250);
DISPLAY INVISIBLE (-7125 -1250);
FORCEPROP 1 LAST PATH I34
J 0
(-7075 -1225);
DISPLAY 0.872340 (-7075 -1225);
PAINT AQUA (-7075 -1225);
DISPLAY INVISIBLE (-7075 -1225);
FORCEADD UNIVERSAL_GND..1
(-6700 -1800);
FORCEPROP 3 LASTPIN (-6700 -1750) SIG_NAME GND\g
J 0
(-6690 -1740);
DISPLAY 0.659574 (-6690 -1740);
PAINT MONO (-6690 -1740);
DISPLAY INVISIBLE (-6690 -1740);
FORCEPROP 2 LAST CDS_LIB logical_power
J 0
(-6700 -1800);
PAINT MONO (-6700 -1800);
DISPLAY INVISIBLE (-6700 -1800);
FORCEPROP 1 LAST HDL_POWER GND
J 1
(-6675 -1875);
DISPLAY 0.872340 (-6675 -1875);
PAINT GREEN (-6675 -1875);
DISPLAY INVISIBLE (-6675 -1875);
FORCEPROP 1 LAST PATH I35
J 0
(-6625 -1800);
DISPLAY 0.872340 (-6625 -1800);
PAINT AQUA (-6625 -1800);
DISPLAY INVISIBLE (-6625 -1800);
FORCEPROP 2 LAST ROOM VR_CORE0_CTRL
J 0
(-6972 -1678);
DISPLAY INVISIBLE (-6972 -1678);
FORCEADD Q_CAP..1
(-6700 -1575);
FORCEPROP 1 LAST PART_NUMBER CH5222KEB01
J 0
(-6650 -1700);
DISPLAY 0.617021 (-6650 -1700);
PAINT BLUE (-6650 -1700);
DISPLAY INVISIBLE (-6650 -1700);
FORCEPROP 1 LAST MATERIAL X6S
J 0
(-6650 -1650);
DISPLAY 0.617021 (-6650 -1650);
PAINT SKYBLUE (-6650 -1650);
FORCEPROP 1 LAST TOLERANCE 10%
J 0
(-6650 -1600);
DISPLAY 0.617021 (-6650 -1600);
PAINT SKYBLUE (-6650 -1600);
FORCEPROP 1 LAST VALUE 2.2UF
J 0
(-6650 -1500);
DISPLAY 0.617021 (-6650 -1500);
PAINT SKYBLUE (-6650 -1500);
FORCEPROP 1 LAST VOLTAGE 10V
J 0
(-6650 -1550);
DISPLAY 0.617021 (-6650 -1550);
PAINT SKYBLUE (-6650 -1550);
FORCEPROP 1 LAST PACK_TYPE C0402
J 0
(-6650 -1750);
DISPLAY 0.617021 (-6650 -1750);
PAINT SKYBLUE (-6650 -1750);
FORCEPROP 1 LAST LOCATION PC229_P0_7
J 0
(-6650 -1450);
DISPLAY 0.617021 (-6650 -1450);
PAINT AQUA (-6650 -1450);
FORCEPROP 1 LASTPIN (-6700 -1475) $PN 1
J 0
(-6690 -1495);
DISPLAY 0.617021 (-6690 -1495);
PAINT MONO (-6690 -1495);
FORCEPROP 1 LASTPIN (-6700 -1675) $PN 2
J 0
(-6690 -1695);
DISPLAY 0.617021 (-6690 -1695);
PAINT MONO (-6690 -1695);
FORCEPROP 2 LAST CDS_LIB pure_quanta
J 0
(-6700 -1575);
DISPLAY INVISIBLE (-6700 -1575);
FORCEPROP 1 LAST PATH I36
J 0
(-6650 -1425);
DISPLAY 0.978723 (-6650 -1425);
PAINT WHITE (-6650 -1425);
DISPLAY INVISIBLE (-6650 -1425);
FORCEPROP 1 LAST LOCATION PC229_P0_7
J 0
(-6650 -1400);
DISPLAY 1.021277 (-6650 -1400);
PAINT AQUA (-6650 -1400);
DISPLAY INVISIBLE (-6650 -1400);
FORCEPROP 0 LAST $SEC 1
J 0
(-6650 -1400);
DISPLAY 0.680851 (-6650 -1400);
PAINT MONO (-6650 -1400);
DISPLAY INVISIBLE (-6650 -1400);
FORCEPROP 0 LAST CDS_SEC 1
J 0
(-6650 -1400);
DISPLAY 1.021277 (-6650 -1400);
DISPLAY INVISIBLE (-6650 -1400);
FORCEADD UNIVERSAL_GND..1
(-4950 -3300);
FORCEPROP 3 LASTPIN (-4950 -3250) SIG_NAME GND\g
J 0
(-4940 -3240);
DISPLAY 0.659574 (-4940 -3240);
PAINT MONO (-4940 -3240);
DISPLAY INVISIBLE (-4940 -3240);
FORCEPROP 2 LAST CDS_LIB logical_power
J 0
(-4950 -3300);
PAINT MONO (-4950 -3300);
DISPLAY INVISIBLE (-4950 -3300);
FORCEPROP 1 LAST HDL_POWER GND
J 1
(-4925 -3375);
DISPLAY 0.872340 (-4925 -3375);
PAINT GREEN (-4925 -3375);
DISPLAY INVISIBLE (-4925 -3375);
FORCEPROP 1 LAST PATH I37
J 0
(-4875 -3300);
DISPLAY 0.872340 (-4875 -3300);
PAINT AQUA (-4875 -3300);
DISPLAY INVISIBLE (-4875 -3300);
FORCEPROP 2 LAST ROOM VR_CORE0_CTRL
J 0
(-5222 -3178);
DISPLAY INVISIBLE (-5222 -3178);
FORCEADD UNIVERSAL_GND..1
(-4550 -2925);
FORCEPROP 3 LASTPIN (-4550 -2875) SIG_NAME GND\g
J 0
(-4540 -2865);
DISPLAY 0.659574 (-4540 -2865);
PAINT MONO (-4540 -2865);
DISPLAY INVISIBLE (-4540 -2865);
FORCEPROP 2 LAST CDS_LIB logical_power
J 0
(-4550 -2925);
DISPLAY INVISIBLE (-4550 -2925);
FORCEPROP 1 LAST HDL_POWER GND
J 1
(-4525 -3000);
DISPLAY 0.872340 (-4525 -3000);
PAINT GREEN (-4525 -3000);
DISPLAY INVISIBLE (-4525 -3000);
FORCEPROP 1 LAST PATH I38
J 0
(-4475 -2925);
DISPLAY 0.872340 (-4475 -2925);
PAINT AQUA (-4475 -2925);
DISPLAY INVISIBLE (-4475 -2925);
FORCEADD Q_INDUCTOR..1
R 2
(-4325 -2800);
FORCEPROP 1 LAST PART_NUMBER CV+12^0EZ03
J 2
(-4200 -2690);
DISPLAY 0.617021 (-4200 -2690);
PAINT BLUE (-4200 -2690);
DISPLAY INVISIBLE (-4200 -2690);
FORCEPROP 2 LAST VALUE 120NH/69A
J 2
(-4200 -2550);
DISPLAY 0.617021 (-4200 -2550);
PAINT SKYBLUE (-4200 -2550);
FORCEPROP 2 LAST PACK_TYPE SMLF
J 2
(-4200 -2600);
DISPLAY 0.617021 (-4200 -2600);
PAINT SKYBLUE (-4200 -2600);
FORCEPROP 1 LAST MATERIAL IND
J 2
(-4200 -2745);
DISPLAY 0.617021 (-4200 -2745);
PAINT SKYBLUE (-4200 -2745);
FORCEPROP 1 LAST LOCATION PL105
J 2
(-4200 -2640);
DISPLAY 0.617021 (-4200 -2640);
PAINT AQUA (-4200 -2640);
FORCEPROP 0 LASTPIN (-4225 -2825) $PN 1
J 0
(-4215 -2815);
DISPLAY 0.617021 (-4215 -2815);
PAINT MONO (-4215 -2815);
FORCEPROP 0 LASTPIN (-4425 -2825) $PN 2
J 2
(-4435 -2815);
DISPLAY 0.617021 (-4435 -2815);
PAINT MONO (-4435 -2815);
FORCEPROP 2 LAST CDS_LIB pure_quanta
J 2
(-4325 -2800);
DISPLAY INVISIBLE (-4325 -2800);
FORCEPROP 1 LAST NEEDS_NO_SIZE TRUE
J 2
(-4325 -2800);
DISPLAY 0.468085 (-4325 -2800);
PAINT GREEN (-4325 -2800);
DISPLAY INVISIBLE (-4325 -2800);
FORCEPROP 1 LAST PATH I39
J 2
(-4400 -2745);
DISPLAY 0.723404 (-4400 -2745);
PAINT GREEN (-4400 -2745);
DISPLAY INVISIBLE (-4400 -2745);
FORCEPROP 0 LAST $SEC 1
J 2
(-4200 -2500);
DISPLAY 0.680851 (-4200 -2500);
PAINT MONO (-4200 -2500);
DISPLAY INVISIBLE (-4200 -2500);
FORCEPROP 0 LAST CDS_SEC 1
J 2
(-4200 -2500);
DISPLAY 1.021277 (-4200 -2500);
DISPLAY INVISIBLE (-4200 -2500);
FORCEADD Q_RES..2
R 2
(-7550 -5900);
FORCEPROP 1 LAST PART_NUMBER CS28872FB01
J 2
(-7590 -6025);
DISPLAY 0.617021 (-7590 -6025);
PAINT BLUE (-7590 -6025);
DISPLAY INVISIBLE (-7590 -6025);
FORCEPROP 1 LAST WATTAGE 1/16W
J 2
(-7590 -5925);
DISPLAY 0.617021 (-7590 -5925);
PAINT SKYBLUE (-7590 -5925);
FORCEPROP 1 LAST MATERIAL EMPTY
J 2
(-7590 -5975);
DISPLAY 0.617021 (-7590 -5975);
PAINT RED (-7590 -5975);
FORCEPROP 1 LAST TOLERANCE 1%
J 2
(-7595 -5875);
DISPLAY 0.617021 (-7595 -5875);
PAINT SKYBLUE (-7595 -5875);
FORCEPROP 1 LAST VALUE 8.87K
J 2
(-7595 -5825);
DISPLAY 0.617021 (-7595 -5825);
PAINT SKYBLUE (-7595 -5825);
FORCEPROP 1 LAST PACK_TYPE 0402LF
J 2
(-7590 -6075);
DISPLAY 0.617021 (-7590 -6075);
PAINT SKYBLUE (-7590 -6075);
FORCEPROP 1 LAST LOCATION PR132
J 2
(-7595 -5775);
DISPLAY 0.617021 (-7595 -5775);
PAINT AQUA (-7595 -5775);
FORCEPROP 1 LASTPIN (-7550 -5800) $PN 1
J 2
(-7555 -5838);
DISPLAY 0.617021 (-7555 -5838);
PAINT MONO (-7555 -5838);
FORCEPROP 1 LASTPIN (-7550 -6000) $PN 2
J 2
(-7555 -5990);
DISPLAY 0.617021 (-7555 -5990);
PAINT MONO (-7555 -5990);
FORCEPROP 2 LAST CDS_LIB pure_quanta
J 2
(-7550 -5900);
DISPLAY INVISIBLE (-7550 -5900);
FORCEPROP 1 LAST PATH I4
J 2
(-7600 -5725);
DISPLAY 0.978723 (-7600 -5725);
PAINT WHITE (-7600 -5725);
DISPLAY INVISIBLE (-7600 -5725);
FORCEPROP 0 LAST $SEC 1
J 0
(-7575 -5725);
DISPLAY 0.680851 (-7575 -5725);
PAINT MONO (-7575 -5725);
DISPLAY INVISIBLE (-7575 -5725);
FORCEPROP 0 LAST CDS_SEC 1
J 0
(-7575 -5725);
DISPLAY 1.021277 (-7575 -5725);
DISPLAY INVISIBLE (-7575 -5725);
FORCEADD Q_RES..1
(-4350 -2125);
FORCEPROP 1 LAST PART_NUMBER CS-3302FB01
J 0
(-4450 -2075);
DISPLAY 0.617021 (-4450 -2075);
PAINT BLUE (-4450 -2075);
DISPLAY INVISIBLE (-4450 -2075);
FORCEPROP 1 LAST VALUE 3.3
J 2
(-4100 -2125);
DISPLAY 0.617021 (-4100 -2125);
PAINT SKYBLUE (-4100 -2125);
FORCEPROP 1 LAST WATTAGE 1/16W
J 2
(-4125 -2025);
DISPLAY 0.617021 (-4125 -2025);
PAINT SKYBLUE (-4125 -2025);
FORCEPROP 1 LAST TOLERANCE 1%
J 0
(-4075 -2125);
DISPLAY 0.617021 (-4075 -2125);
PAINT SKYBLUE (-4075 -2125);
FORCEPROP 1 LAST PACK_TYPE 0402LF
J 0
(-4450 -2025);
DISPLAY 0.617021 (-4450 -2025);
PAINT SKYBLUE (-4450 -2025);
FORCEPROP 1 LAST MATERIAL CHIP
J 0
(-4450 -1975);
DISPLAY 0.617021 (-4450 -1975);
PAINT SKYBLUE (-4450 -1975);
FORCEPROP 1 LAST LOCATION PR1773
J 0
(-4600 -2125);
DISPLAY 0.617021 (-4600 -2125);
PAINT AQUA (-4600 -2125);
FORCEPROP 1 LASTPIN (-4450 -2125) $PN 1
J 0
(-4438 -2113);
DISPLAY 0.617021 (-4438 -2113);
FORCEPROP 1 LASTPIN (-4250 -2125) $PN 2
J 0
(-4288 -2113);
DISPLAY 0.617021 (-4288 -2113);
FORCEPROP 2 LAST CDS_LIB pure_quanta
J 0
(-4350 -2125);
PAINT MONO (-4350 -2125);
DISPLAY INVISIBLE (-4350 -2125);
FORCEPROP 1 LAST PATH I40
J 0
(-4400 -1975);
DISPLAY 0.978723 (-4400 -1975);
PAINT WHITE (-4400 -1975);
DISPLAY INVISIBLE (-4400 -1975);
FORCEPROP 2 LAST $SEC 1
J 0
(-4400 -1925);
DISPLAY 0.680851 (-4400 -1925);
PAINT MONO (-4400 -1925);
DISPLAY INVISIBLE (-4400 -1925);
FORCEPROP 2 LAST CDS_SEC 1
J 0
(-4400 -1925);
DISPLAY 1.021277 (-4400 -1925);
DISPLAY INVISIBLE (-4400 -1925);
FORCEADD Q_CAP..1
(-4800 -1675);
FORCEPROP 1 LAST PART_NUMBER TMP_QCH2336K1B12
J 0
(-4750 -1825);
DISPLAY 0.617021 (-4750 -1825);
PAINT BLUE (-4750 -1825);
DISPLAY INVISIBLE (-4750 -1825);
FORCEPROP 1 LAST MATERIAL X7R
J 0
(-4750 -1725);
DISPLAY 0.617021 (-4750 -1725);
PAINT SKYBLUE (-4750 -1725);
FORCEPROP 1 LAST TOLERANCE 10%
J 0
(-4750 -1675);
DISPLAY 0.617021 (-4750 -1675);
PAINT SKYBLUE (-4750 -1675);
FORCEPROP 1 LAST VALUE 3300PF
J 0
(-4750 -1575);
DISPLAY 0.617021 (-4750 -1575);
PAINT SKYBLUE (-4750 -1575);
FORCEPROP 1 LAST VOLTAGE 50V
J 0
(-4750 -1625);
DISPLAY 0.617021 (-4750 -1625);
PAINT SKYBLUE (-4750 -1625);
FORCEPROP 1 LAST PACK_TYPE 0402
J 0
(-4750 -1775);
DISPLAY 0.617021 (-4750 -1775);
PAINT SKYBLUE (-4750 -1775);
FORCEPROP 1 LAST LOCATION PC231_P0_7
J 0
(-4750 -1525);
DISPLAY 0.617021 (-4750 -1525);
PAINT AQUA (-4750 -1525);
FORCEPROP 1 LASTPIN (-4800 -1575) $PN 1
J 0
(-4790 -1595);
DISPLAY 0.617021 (-4790 -1595);
PAINT MONO (-4790 -1595);
FORCEPROP 1 LASTPIN (-4800 -1775) $PN 2
J 0
(-4790 -1795);
DISPLAY 0.617021 (-4790 -1795);
PAINT MONO (-4790 -1795);
FORCEPROP 2 LAST CDS_LIB pure_quanta
J 0
(-4800 -1675);
DISPLAY INVISIBLE (-4800 -1675);
FORCEPROP 1 LAST PATH I41
J 0
(-4750 -1525);
DISPLAY 0.978723 (-4750 -1525);
PAINT WHITE (-4750 -1525);
DISPLAY INVISIBLE (-4750 -1525);
FORCEPROP 1 LAST LOCATION PC231_P0_7
J 0
(-4750 -1475);
DISPLAY 1.021277 (-4750 -1475);
PAINT AQUA (-4750 -1475);
DISPLAY INVISIBLE (-4750 -1475);
FORCEPROP 0 LAST $SEC 1
J 0
(-4750 -1475);
DISPLAY 0.680851 (-4750 -1475);
PAINT MONO (-4750 -1475);
DISPLAY INVISIBLE (-4750 -1475);
FORCEPROP 0 LAST CDS_SEC 1
J 0
(-4750 -1475);
DISPLAY 1.021277 (-4750 -1475);
DISPLAY INVISIBLE (-4750 -1475);
FORCEADD Q_CAP..1
(-4400 -1675);
FORCEPROP 1 LAST PART_NUMBER CH5103KEB01
J 0
(-4350 -1825);
DISPLAY 0.617021 (-4350 -1825);
PAINT BLUE (-4350 -1825);
DISPLAY INVISIBLE (-4350 -1825);
FORCEPROP 1 LAST MATERIAL X6S
J 0
(-4350 -1725);
DISPLAY 0.617021 (-4350 -1725);
PAINT SKYBLUE (-4350 -1725);
FORCEPROP 1 LAST PACK_TYPE C0402
J 0
(-4350 -1775);
DISPLAY 0.617021 (-4350 -1775);
PAINT SKYBLUE (-4350 -1775);
FORCEPROP 1 LAST TOLERANCE 10%
J 0
(-4350 -1675);
DISPLAY 0.617021 (-4350 -1675);
PAINT SKYBLUE (-4350 -1675);
FORCEPROP 1 LAST VOLTAGE 16V
J 0
(-4350 -1625);
DISPLAY 0.617021 (-4350 -1625);
PAINT SKYBLUE (-4350 -1625);
FORCEPROP 1 LAST VALUE 1UF
J 0
(-4350 -1575);
DISPLAY 0.617021 (-4350 -1575);
PAINT SKYBLUE (-4350 -1575);
FORCEPROP 1 LAST LOCATION PC233_P0_7
J 0
(-4350 -1525);
DISPLAY 0.617021 (-4350 -1525);
PAINT AQUA (-4350 -1525);
FORCEPROP 1 LASTPIN (-4400 -1575) $PN 1
J 0
(-4390 -1595);
DISPLAY 0.617021 (-4390 -1595);
PAINT MONO (-4390 -1595);
FORCEPROP 1 LASTPIN (-4400 -1775) $PN 2
J 0
(-4390 -1795);
DISPLAY 0.617021 (-4390 -1795);
PAINT MONO (-4390 -1795);
FORCEPROP 2 LAST CDS_LIB pure_quanta
J 0
(-4400 -1675);
DISPLAY INVISIBLE (-4400 -1675);
FORCEPROP 1 LAST PATH I42
J 0
(-4350 -1525);
DISPLAY 0.978723 (-4350 -1525);
PAINT WHITE (-4350 -1525);
DISPLAY INVISIBLE (-4350 -1525);
FORCEPROP 1 LAST LOCATION PC233_P0_7
J 0
(-4350 -1475);
DISPLAY 1.021277 (-4350 -1475);
PAINT AQUA (-4350 -1475);
DISPLAY INVISIBLE (-4350 -1475);
FORCEPROP 0 LAST $SEC 1
J 0
(-4350 -1475);
DISPLAY 0.680851 (-4350 -1475);
PAINT MONO (-4350 -1475);
DISPLAY INVISIBLE (-4350 -1475);
FORCEPROP 0 LAST CDS_SEC 1
J 0
(-4350 -1475);
DISPLAY 1.021277 (-4350 -1475);
DISPLAY INVISIBLE (-4350 -1475);
FORCEADD Q_CAP..1
(-4000 -1675);
FORCEPROP 1 LAST PART_NUMBER CH6223MEA01
J 0
(-3950 -1825);
DISPLAY 0.617021 (-3950 -1825);
PAINT BLUE (-3950 -1825);
DISPLAY INVISIBLE (-3950 -1825);
FORCEPROP 1 LAST MATERIAL X6S
J 0
(-3950 -1725);
DISPLAY 0.617021 (-3950 -1725);
PAINT SKYBLUE (-3950 -1725);
FORCEPROP 1 LAST TOLERANCE 20%
J 0
(-3950 -1675);
DISPLAY 0.617021 (-3950 -1675);
PAINT SKYBLUE (-3950 -1675);
FORCEPROP 1 LAST VALUE 22UF
J 0
(-3950 -1575);
DISPLAY 0.617021 (-3950 -1575);
PAINT SKYBLUE (-3950 -1575);
FORCEPROP 1 LAST VOLTAGE 16V
J 0
(-3950 -1625);
DISPLAY 0.617021 (-3950 -1625);
PAINT SKYBLUE (-3950 -1625);
FORCEPROP 1 LAST PACK_TYPE C0805
J 0
(-3950 -1775);
DISPLAY 0.617021 (-3950 -1775);
PAINT SKYBLUE (-3950 -1775);
FORCEPROP 1 LAST LOCATION PC237_P0_7
J 0
(-3950 -1525);
DISPLAY 0.617021 (-3950 -1525);
PAINT AQUA (-3950 -1525);
FORCEPROP 1 LASTPIN (-4000 -1575) $PN 1
J 0
(-3990 -1595);
DISPLAY 0.617021 (-3990 -1595);
PAINT MONO (-3990 -1595);
FORCEPROP 1 LASTPIN (-4000 -1775) $PN 2
J 0
(-3990 -1795);
DISPLAY 0.617021 (-3990 -1795);
PAINT MONO (-3990 -1795);
FORCEPROP 2 LAST CDS_LIB pure_quanta
J 0
(-4000 -1675);
DISPLAY INVISIBLE (-4000 -1675);
FORCEPROP 1 LAST PATH I43
J 0
(-3950 -1525);
DISPLAY 0.978723 (-3950 -1525);
PAINT WHITE (-3950 -1525);
DISPLAY INVISIBLE (-3950 -1525);
FORCEPROP 1 LAST LOCATION PC237_P0_7
J 0
(-3950 -1475);
DISPLAY 1.021277 (-3950 -1475);
PAINT AQUA (-3950 -1475);
DISPLAY INVISIBLE (-3950 -1475);
FORCEPROP 0 LAST $SEC 1
J 0
(-3950 -1475);
DISPLAY 0.680851 (-3950 -1475);
PAINT MONO (-3950 -1475);
DISPLAY INVISIBLE (-3950 -1475);
FORCEPROP 0 LAST CDS_SEC 1
J 0
(-3950 -1475);
DISPLAY 1.021277 (-3950 -1475);
DISPLAY INVISIBLE (-3950 -1475);
FORCEADD Q_INDUCTOR4P_14..1
(-3175 -5525);
FORCEPROP 1 LAST PART_NUMBER CV+15^0TZ04
J 0
(-3400 -5365);
DISPLAY 0.617021 (-3400 -5365);
PAINT BLUE (-3400 -5365);
DISPLAY INVISIBLE (-3400 -5365);
FORCEPROP 1 LAST MATERIAL IND
J 0
(-3400 -5315);
DISPLAY 0.617021 (-3400 -5315);
PAINT SKYBLUE (-3400 -5315);
FORCEPROP 2 LAST VALUE 150NH
J 0
(-3400 -5225);
DISPLAY 0.617021 (-3400 -5225);
PAINT SKYBLUE (-3400 -5225);
FORCEPROP 2 LAST PART_TYPE SMLF
J 0
(-3400 -5175);
DISPLAY 1.021277 (-3400 -5175);
FORCEPROP 1 LAST LOCATION PL7
J 0
(-3400 -5270);
DISPLAY 0.617021 (-3400 -5270);
PAINT AQUA (-3400 -5270);
FORCEPROP 2 LASTPIN (-3575 -5400) $PN 1
J 2
(-3585 -5390);
DISPLAY 0.617021 (-3585 -5390);
PAINT MONO (-3585 -5390);
FORCEPROP 2 LASTPIN (-3575 -5650) $PN 2
J 2
(-3585 -5640);
DISPLAY 0.617021 (-3585 -5640);
PAINT MONO (-3585 -5640);
FORCEPROP 2 LASTPIN (-2775 -5650) $PN 3
J 0
(-2765 -5640);
DISPLAY 0.617021 (-2765 -5640);
PAINT MONO (-2765 -5640);
FORCEPROP 2 LASTPIN (-2775 -5400) $PN 4
J 0
(-2765 -5390);
DISPLAY 0.617021 (-2765 -5390);
PAINT MONO (-2765 -5390);
FORCEPROP 2 LAST SEC_TYPE 
J 0
(-3400 -5125);
DISPLAY 1.021277 (-3400 -5125);
DISPLAY INVISIBLE (-3400 -5125);
FORCEPROP 2 LAST CDS_LIB pure_quanta
J 0
(-3175 -5525);
DISPLAY INVISIBLE (-3175 -5525);
FORCEPROP 1 LAST NEEDS_NO_SIZE TRUE
J 0
(-3175 -5525);
DISPLAY 0.468085 (-3175 -5525);
PAINT GREEN (-3175 -5525);
DISPLAY INVISIBLE (-3175 -5525);
FORCEPROP 1 LAST PATH I44
J 0
(-2975 -5370);
DISPLAY 0.723404 (-2975 -5370);
PAINT GREEN (-2975 -5370);
DISPLAY INVISIBLE (-2975 -5370);
FORCEPROP 2 LAST SEC 1
J 0
(-3400 -5125);
DISPLAY 0.680851 (-3400 -5125);
PAINT MONO (-3400 -5125);
DISPLAY INVISIBLE (-3400 -5125);
FORCEADD Q_CAP..1
R 2
(-3650 -5125);
FORCEPROP 1 LAST PART_NUMBER CH4106K1B01
J 2
(-3675 -5250);
DISPLAY 0.617021 (-3675 -5250);
PAINT BLUE (-3675 -5250);
DISPLAY INVISIBLE (-3675 -5250);
FORCEPROP 1 LAST VALUE 100NF
J 2
(-3700 -5050);
DISPLAY 0.617021 (-3700 -5050);
PAINT SKYBLUE (-3700 -5050);
FORCEPROP 1 LAST VOLTAGE 50V
J 2
(-3700 -5100);
DISPLAY 0.617021 (-3700 -5100);
PAINT SKYBLUE (-3700 -5100);
FORCEPROP 1 LAST PACK_TYPE C0402
J 2
(-3700 -5300);
DISPLAY 0.617021 (-3700 -5300);
PAINT SKYBLUE (-3700 -5300);
FORCEPROP 1 LAST MATERIAL X7R
J 2
(-3700 -5200);
DISPLAY 0.617021 (-3700 -5200);
PAINT SKYBLUE (-3700 -5200);
FORCEPROP 1 LAST TOLERANCE 10%
J 2
(-3700 -5150);
DISPLAY 0.617021 (-3700 -5150);
PAINT SKYBLUE (-3700 -5150);
FORCEPROP 1 LAST LOCATION PC234
J 2
(-3700 -5000);
DISPLAY 0.617021 (-3700 -5000);
PAINT AQUA (-3700 -5000);
FORCEPROP 1 LASTPIN (-3650 -5025) $PN 1
J 2
(-3660 -5045);
DISPLAY 0.617021 (-3660 -5045);
FORCEPROP 1 LASTPIN (-3650 -5225) $PN 2
J 2
(-3660 -5245);
DISPLAY 0.617021 (-3660 -5245);
FORCEPROP 2 LAST CDS_LIB pure_quanta
J 2
(-3650 -5125);
PAINT MONO (-3650 -5125);
DISPLAY INVISIBLE (-3650 -5125);
FORCEPROP 1 LAST PATH I45
J 2
(-3700 -4975);
DISPLAY 0.978723 (-3700 -4975);
PAINT WHITE (-3700 -4975);
DISPLAY INVISIBLE (-3700 -4975);
FORCEPROP 2 LAST $SEC 1
J 0
(-3700 -4925);
DISPLAY 0.680851 (-3700 -4925);
PAINT MONO (-3700 -4925);
DISPLAY INVISIBLE (-3700 -4925);
FORCEPROP 2 LAST CDS_SEC 1
J 0
(-3700 -4925);
DISPLAY 1.021277 (-3700 -4925);
DISPLAY INVISIBLE (-3700 -4925);
FORCEADD Q_RES..1
(-3150 -5900);
FORCEPROP 1 LAST PART_NUMBER CS00002JB13
J 0
(-3275 -5850);
DISPLAY 0.617021 (-3275 -5850);
PAINT BLUE (-3275 -5850);
DISPLAY INVISIBLE (-3275 -5850);
FORCEPROP 1 LAST WATTAGE 1/16W
J 2
(-2900 -5800);
DISPLAY 0.617021 (-2900 -5800);
PAINT SKYBLUE (-2900 -5800);
FORCEPROP 1 LAST MATERIAL CHIP
J 0
(-2875 -5900);
DISPLAY 0.617021 (-2875 -5900);
PAINT SKYBLUE (-2875 -5900);
FORCEPROP 1 LAST TOLERANCE 5%
J 0
(-2950 -5900);
DISPLAY 0.617021 (-2950 -5900);
PAINT SKYBLUE (-2950 -5900);
FORCEPROP 1 LAST VALUE 0
J 2
(-2975 -5900);
DISPLAY 0.617021 (-2975 -5900);
PAINT SKYBLUE (-2975 -5900);
FORCEPROP 1 LAST PACK_TYPE 0402LF
J 0
(-3275 -5800);
DISPLAY 0.617021 (-3275 -5800);
PAINT SKYBLUE (-3275 -5800);
FORCEPROP 1 LAST LOCATION PR136
J 0
(-3425 -5900);
DISPLAY 0.617021 (-3425 -5900);
PAINT AQUA (-3425 -5900);
FORCEPROP 1 LASTPIN (-3250 -5900) $PN 1
J 0
(-3238 -5888);
DISPLAY 0.617021 (-3238 -5888);
PAINT MONO (-3238 -5888);
FORCEPROP 1 LASTPIN (-3050 -5900) $PN 2
J 0
(-3088 -5888);
DISPLAY 0.617021 (-3088 -5888);
PAINT MONO (-3088 -5888);
FORCEPROP 2 LAST CDS_LIB pure_quanta
J 0
(-3150 -5900);
DISPLAY INVISIBLE (-3150 -5900);
FORCEPROP 1 LAST PATH I46
J 0
(-3200 -5750);
DISPLAY 0.978723 (-3200 -5750);
PAINT WHITE (-3200 -5750);
DISPLAY INVISIBLE (-3200 -5750);
FORCEPROP 0 LAST $SEC 1
J 0
(-2900 -5750);
DISPLAY 0.680851 (-2900 -5750);
PAINT MONO (-2900 -5750);
DISPLAY INVISIBLE (-2900 -5750);
FORCEPROP 0 LAST CDS_SEC 1
J 0
(-2900 -5750);
DISPLAY 1.021277 (-2900 -5750);
DISPLAY INVISIBLE (-2900 -5750);
FORCEADD Q_CAP..1
(-3625 -4500);
FORCEPROP 1 LAST PART_NUMBER CH6223MEA01
J 0
(-3575 -4650);
DISPLAY 0.617021 (-3575 -4650);
PAINT BLUE (-3575 -4650);
DISPLAY INVISIBLE (-3575 -4650);
FORCEPROP 1 LAST PACK_TYPE C0805
J 0
(-3575 -4600);
DISPLAY 0.617021 (-3575 -4600);
PAINT SKYBLUE (-3575 -4600);
FORCEPROP 1 LAST VALUE 22UF
J 0
(-3575 -4400);
DISPLAY 0.617021 (-3575 -4400);
PAINT SKYBLUE (-3575 -4400);
FORCEPROP 1 LAST MATERIAL X6S
J 0
(-3575 -4550);
DISPLAY 0.617021 (-3575 -4550);
PAINT SKYBLUE (-3575 -4550);
FORCEPROP 1 LAST TOLERANCE 20%
J 0
(-3575 -4500);
DISPLAY 0.617021 (-3575 -4500);
PAINT SKYBLUE (-3575 -4500);
FORCEPROP 1 LAST VOLTAGE 16V
J 0
(-3575 -4450);
DISPLAY 0.617021 (-3575 -4450);
PAINT SKYBLUE (-3575 -4450);
FORCEPROP 1 LAST LOCATION PC238_P0_8
J 0
(-3575 -4350);
DISPLAY 0.617021 (-3575 -4350);
PAINT AQUA (-3575 -4350);
FORCEPROP 1 LASTPIN (-3625 -4400) $PN 1
J 0
(-3615 -4420);
DISPLAY 0.617021 (-3615 -4420);
PAINT MONO (-3615 -4420);
FORCEPROP 1 LASTPIN (-3625 -4600) $PN 2
J 0
(-3615 -4620);
DISPLAY 0.617021 (-3615 -4620);
PAINT MONO (-3615 -4620);
FORCEPROP 2 LAST CDS_LIB pure_quanta
J 0
(-3625 -4500);
DISPLAY INVISIBLE (-3625 -4500);
FORCEPROP 1 LAST PATH I47
J 0
(-3575 -4350);
DISPLAY 0.978723 (-3575 -4350);
PAINT WHITE (-3575 -4350);
DISPLAY INVISIBLE (-3575 -4350);
FORCEPROP 1 LAST LOCATION PC238_P0_8
J 0
(-3575 -4300);
DISPLAY 1.021277 (-3575 -4300);
PAINT AQUA (-3575 -4300);
DISPLAY INVISIBLE (-3575 -4300);
FORCEPROP 0 LAST $SEC 1
J 0
(-3575 -4300);
DISPLAY 0.680851 (-3575 -4300);
PAINT MONO (-3575 -4300);
DISPLAY INVISIBLE (-3575 -4300);
FORCEPROP 0 LAST CDS_SEC 1
J 0
(-3575 -4300);
DISPLAY 1.021277 (-3575 -4300);
DISPLAY INVISIBLE (-3575 -4300);
FORCEADD Q_CAP..1
(-3250 -4500);
FORCEPROP 1 LAST PART_NUMBER CH6223MEA01
J 0
(-3200 -4650);
DISPLAY 0.617021 (-3200 -4650);
PAINT BLUE (-3200 -4650);
DISPLAY INVISIBLE (-3200 -4650);
FORCEPROP 1 LAST PACK_TYPE C0805
J 0
(-3200 -4600);
DISPLAY 0.617021 (-3200 -4600);
PAINT SKYBLUE (-3200 -4600);
FORCEPROP 1 LAST MATERIAL X6S
J 0
(-3200 -4550);
DISPLAY 0.617021 (-3200 -4550);
PAINT SKYBLUE (-3200 -4550);
FORCEPROP 1 LAST TOLERANCE 20%
J 0
(-3200 -4500);
DISPLAY 0.617021 (-3200 -4500);
PAINT SKYBLUE (-3200 -4500);
FORCEPROP 1 LAST VOLTAGE 16V
J 0
(-3200 -4450);
DISPLAY 0.617021 (-3200 -4450);
PAINT SKYBLUE (-3200 -4450);
FORCEPROP 1 LAST VALUE 22UF
J 0
(-3200 -4400);
DISPLAY 0.617021 (-3200 -4400);
PAINT SKYBLUE (-3200 -4400);
FORCEPROP 1 LAST LOCATION PC240_P0_8
J 0
(-3200 -4350);
DISPLAY 0.617021 (-3200 -4350);
PAINT AQUA (-3200 -4350);
FORCEPROP 1 LASTPIN (-3250 -4400) $PN 1
J 0
(-3240 -4420);
DISPLAY 0.617021 (-3240 -4420);
PAINT MONO (-3240 -4420);
FORCEPROP 1 LASTPIN (-3250 -4600) $PN 2
J 0
(-3240 -4620);
DISPLAY 0.617021 (-3240 -4620);
PAINT MONO (-3240 -4620);
FORCEPROP 2 LAST CDS_LIB pure_quanta
J 0
(-3250 -4500);
DISPLAY INVISIBLE (-3250 -4500);
FORCEPROP 1 LAST PATH I48
J 0
(-3200 -4350);
DISPLAY 0.978723 (-3200 -4350);
PAINT WHITE (-3200 -4350);
DISPLAY INVISIBLE (-3200 -4350);
FORCEPROP 1 LAST LOCATION PC240_P0_8
J 0
(-3200 -4300);
DISPLAY 1.021277 (-3200 -4300);
PAINT AQUA (-3200 -4300);
DISPLAY INVISIBLE (-3200 -4300);
FORCEPROP 0 LAST $SEC 1
J 0
(-3200 -4300);
DISPLAY 0.680851 (-3200 -4300);
PAINT MONO (-3200 -4300);
DISPLAY INVISIBLE (-3200 -4300);
FORCEPROP 0 LAST CDS_SEC 1
J 0
(-3200 -4300);
DISPLAY 1.021277 (-3200 -4300);
DISPLAY INVISIBLE (-3200 -4300);
FORCEADD UNIVERSAL_GND..1
(-3025 -4925);
FORCEPROP 3 LASTPIN (-3025 -4875) SIG_NAME GND\g
J 0
(-3015 -4865);
DISPLAY 0.659574 (-3015 -4865);
PAINT MONO (-3015 -4865);
DISPLAY INVISIBLE (-3015 -4865);
FORCEPROP 2 LAST CDS_LIB logical_power
J 0
(-3025 -4925);
PAINT MONO (-3025 -4925);
DISPLAY INVISIBLE (-3025 -4925);
FORCEPROP 1 LAST HDL_POWER GND
J 1
(-3000 -5000);
DISPLAY 0.872340 (-3000 -5000);
PAINT GREEN (-3000 -5000);
DISPLAY INVISIBLE (-3000 -5000);
FORCEPROP 1 LAST PATH I49
J 0
(-2950 -4925);
DISPLAY 0.872340 (-2950 -4925);
PAINT AQUA (-2950 -4925);
DISPLAY INVISIBLE (-2950 -4925);
FORCEPROP 2 LAST ROOM VR_CORE0_CTRL
J 0
(-3297 -4803);
DISPLAY INVISIBLE (-3297 -4803);
FORCEADD OFFPAGE..1
(-7075 -6000);
FORCEPROP 2 LAST $XR0 266 
J 0
(-7501 -6000);
DISPLAY 0.638298 (-7501 -6000);
PAINT MONO (-7501 -6000);
FORCEPROP 2 LAST CDS_LIB standard
J 0
(-7075 -6000);
DISPLAY INVISIBLE (-7075 -6000);
FORCEPROP 1 LAST OFFPAGE TRUE
J 0
(-6750 -6125);
DISPLAY 0.872340 (-6750 -6125);
PAINT GREEN (-6750 -6125);
DISPLAY INVISIBLE (-6750 -6125);
FORCEPROP 1 LAST COMMENT_BODY TRUE
J 0
(-6950 -6100);
DISPLAY 0.872340 (-6950 -6100);
PAINT GREEN (-6950 -6100);
DISPLAY INVISIBLE (-6950 -6100);
FORCEPROP 2 LAST PATH I5
J 0
(-7325 -5950);
DISPLAY 1.021277 (-7325 -5950);
DISPLAY INVISIBLE (-7325 -5950);
FORCEADD VCC15..1
(-3025 -4125);
FORCEPROP 3 LASTPIN (-3025 -4175) SIG_NAME SW_P12V_PVCCIN_CPU0_FLT\g
J 0
(-3015 -4165);
DISPLAY 0.659574 (-3015 -4165);
PAINT MONO (-3015 -4165);
DISPLAY INVISIBLE (-3015 -4165);
FORCEPROP 1 LAST HDL_POWER SW_P12V_PVCCIN_CPU0_FLT
J 1
(-2975 -4075);
DISPLAY 0.617021 (-2975 -4075);
PAINT GREEN (-2975 -4075);
FORCEPROP 2 LAST CDS_LIB logical_power
J 0
(-3025 -4125);
DISPLAY INVISIBLE (-3025 -4125);
FORCEPROP 1 LAST PATH I50
J 0
(-2975 -4100);
DISPLAY 0.872340 (-2975 -4100);
PAINT AQUA (-2975 -4100);
DISPLAY INVISIBLE (-2975 -4100);
FORCEADD UNIVERSAL_GND..1
(-2475 -5750);
FORCEPROP 3 LASTPIN (-2475 -5700) SIG_NAME GND\g
J 0
(-2465 -5690);
DISPLAY 0.659574 (-2465 -5690);
PAINT MONO (-2465 -5690);
DISPLAY INVISIBLE (-2465 -5690);
FORCEPROP 2 LAST CDS_LIB logical_power
J 0
(-2475 -5750);
DISPLAY INVISIBLE (-2475 -5750);
FORCEPROP 1 LAST HDL_POWER GND
J 1
(-2450 -5825);
DISPLAY 0.872340 (-2450 -5825);
PAINT GREEN (-2450 -5825);
DISPLAY INVISIBLE (-2450 -5825);
FORCEPROP 1 LAST PATH I51
J 0
(-2400 -5750);
DISPLAY 0.872340 (-2400 -5750);
PAINT AQUA (-2400 -5750);
DISPLAY INVISIBLE (-2400 -5750);
FORCEADD Q_CAP..1
(-1575 -5600);
FORCEPROP 1 LAST PART_NUMBER CH5103KEB01
J 0
(-1525 -5775);
DISPLAY 0.617021 (-1525 -5775);
PAINT BLUE (-1525 -5775);
DISPLAY INVISIBLE (-1525 -5775);
FORCEPROP 1 LAST PACK_TYPE C0402
J 0
(-1525 -5725);
DISPLAY 0.617021 (-1525 -5725);
PAINT SKYBLUE (-1525 -5725);
FORCEPROP 1 LAST TOLERANCE 10%
J 0
(-1525 -5625);
DISPLAY 0.617021 (-1525 -5625);
PAINT SKYBLUE (-1525 -5625);
FORCEPROP 1 LAST VOLTAGE 16V
J 0
(-1525 -5575);
DISPLAY 0.617021 (-1525 -5575);
PAINT SKYBLUE (-1525 -5575);
FORCEPROP 1 LAST VALUE 1UF
J 0
(-1525 -5525);
DISPLAY 0.617021 (-1525 -5525);
PAINT SKYBLUE (-1525 -5525);
FORCEPROP 1 LAST MATERIAL X6S
J 0
(-1525 -5675);
DISPLAY 0.617021 (-1525 -5675);
PAINT SKYBLUE (-1525 -5675);
FORCEPROP 1 LAST LOCATION PC242_P0_8
J 0
(-1525 -5475);
DISPLAY 0.617021 (-1525 -5475);
PAINT AQUA (-1525 -5475);
FORCEPROP 1 LASTPIN (-1575 -5500) $PN 1
J 0
(-1565 -5520);
DISPLAY 0.617021 (-1565 -5520);
PAINT MONO (-1565 -5520);
FORCEPROP 1 LASTPIN (-1575 -5700) $PN 2
J 0
(-1565 -5720);
DISPLAY 0.617021 (-1565 -5720);
PAINT MONO (-1565 -5720);
FORCEPROP 2 LAST CDS_LIB pure_quanta
J 0
(-1575 -5600);
DISPLAY INVISIBLE (-1575 -5600);
FORCEPROP 1 LAST PATH I52
J 0
(-1525 -5450);
DISPLAY 0.978723 (-1525 -5450);
PAINT WHITE (-1525 -5450);
DISPLAY INVISIBLE (-1525 -5450);
FORCEPROP 1 LAST LOCATION PC242_P0_8
J 0
(-1525 -5425);
DISPLAY 1.021277 (-1525 -5425);
PAINT AQUA (-1525 -5425);
DISPLAY INVISIBLE (-1525 -5425);
FORCEPROP 0 LAST $SEC 1
J 0
(-1525 -5425);
DISPLAY 0.680851 (-1525 -5425);
PAINT MONO (-1525 -5425);
DISPLAY INVISIBLE (-1525 -5425);
FORCEPROP 0 LAST CDS_SEC 1
J 0
(-1525 -5425);
DISPLAY 1.021277 (-1525 -5425);
DISPLAY INVISIBLE (-1525 -5425);
FORCEADD Q_CAP..1
(-1150 -5600);
FORCEPROP 1 LAST PART_NUMBER CH622KMEA03
J 0
(-1100 -5775);
DISPLAY 0.617021 (-1100 -5775);
PAINT BLUE (-1100 -5775);
DISPLAY INVISIBLE (-1100 -5775);
FORCEPROP 1 LAST VOLTAGE 4V
J 0
(-1100 -5575);
DISPLAY 0.617021 (-1100 -5575);
PAINT SKYBLUE (-1100 -5575);
FORCEPROP 1 LAST VALUE 22UF
J 0
(-1100 -5525);
DISPLAY 0.617021 (-1100 -5525);
PAINT SKYBLUE (-1100 -5525);
FORCEPROP 1 LAST TOLERANCE 20%
J 0
(-1100 -5625);
DISPLAY 0.617021 (-1100 -5625);
PAINT SKYBLUE (-1100 -5625);
FORCEPROP 1 LAST MATERIAL X6S
J 0
(-1100 -5675);
DISPLAY 0.617021 (-1100 -5675);
PAINT SKYBLUE (-1100 -5675);
FORCEPROP 1 LAST PACK_TYPE C0805
J 0
(-1100 -5725);
DISPLAY 0.617021 (-1100 -5725);
PAINT SKYBLUE (-1100 -5725);
FORCEPROP 1 LAST LOCATION PC244_P0_8
J 0
(-1100 -5475);
DISPLAY 0.617021 (-1100 -5475);
PAINT AQUA (-1100 -5475);
FORCEPROP 1 LASTPIN (-1150 -5500) $PN 1
J 0
(-1140 -5520);
DISPLAY 0.617021 (-1140 -5520);
PAINT MONO (-1140 -5520);
FORCEPROP 1 LASTPIN (-1150 -5700) $PN 2
J 0
(-1140 -5720);
DISPLAY 0.617021 (-1140 -5720);
PAINT MONO (-1140 -5720);
FORCEPROP 2 LAST CDS_LIB pure_quanta
J 0
(-1150 -5600);
DISPLAY INVISIBLE (-1150 -5600);
FORCEPROP 1 LAST PATH I53
J 0
(-1100 -5450);
DISPLAY 0.978723 (-1100 -5450);
PAINT WHITE (-1100 -5450);
DISPLAY INVISIBLE (-1100 -5450);
FORCEPROP 1 LAST LOCATION PC244_P0_8
J 0
(-1100 -5425);
DISPLAY 1.021277 (-1100 -5425);
PAINT AQUA (-1100 -5425);
DISPLAY INVISIBLE (-1100 -5425);
FORCEPROP 0 LAST $SEC 1
J 0
(-1100 -5425);
DISPLAY 0.680851 (-1100 -5425);
PAINT MONO (-1100 -5425);
DISPLAY INVISIBLE (-1100 -5425);
FORCEPROP 0 LAST CDS_SEC 1
J 0
(-1100 -5425);
DISPLAY 1.021277 (-1100 -5425);
DISPLAY INVISIBLE (-1100 -5425);
FORCEADD Q_CAP..1
(-725 -5600);
FORCEPROP 1 LAST PART_NUMBER CH622KMEA03
J 0
(-675 -5775);
DISPLAY 0.617021 (-675 -5775);
PAINT BLUE (-675 -5775);
DISPLAY INVISIBLE (-675 -5775);
FORCEPROP 1 LAST VOLTAGE 4V
J 0
(-675 -5575);
DISPLAY 0.617021 (-675 -5575);
PAINT SKYBLUE (-675 -5575);
FORCEPROP 1 LAST VALUE 22UF
J 0
(-675 -5525);
DISPLAY 0.617021 (-675 -5525);
PAINT SKYBLUE (-675 -5525);
FORCEPROP 1 LAST TOLERANCE 20%
J 0
(-675 -5625);
DISPLAY 0.617021 (-675 -5625);
PAINT SKYBLUE (-675 -5625);
FORCEPROP 1 LAST MATERIAL X6S
J 0
(-675 -5675);
DISPLAY 0.617021 (-675 -5675);
PAINT SKYBLUE (-675 -5675);
FORCEPROP 1 LAST PACK_TYPE C0805
J 0
(-675 -5725);
DISPLAY 0.617021 (-675 -5725);
PAINT SKYBLUE (-675 -5725);
FORCEPROP 1 LAST LOCATION PC246_P0_8
J 0
(-675 -5475);
DISPLAY 0.617021 (-675 -5475);
PAINT AQUA (-675 -5475);
FORCEPROP 1 LASTPIN (-725 -5500) $PN 1
J 0
(-715 -5520);
DISPLAY 0.617021 (-715 -5520);
PAINT MONO (-715 -5520);
FORCEPROP 1 LASTPIN (-725 -5700) $PN 2
J 0
(-715 -5720);
DISPLAY 0.617021 (-715 -5720);
PAINT MONO (-715 -5720);
FORCEPROP 2 LAST CDS_LIB pure_quanta
J 0
(-725 -5600);
DISPLAY INVISIBLE (-725 -5600);
FORCEPROP 1 LAST PATH I54
J 0
(-675 -5450);
DISPLAY 0.978723 (-675 -5450);
PAINT WHITE (-675 -5450);
DISPLAY INVISIBLE (-675 -5450);
FORCEPROP 1 LAST LOCATION PC246_P0_8
J 0
(-675 -5425);
DISPLAY 1.021277 (-675 -5425);
PAINT AQUA (-675 -5425);
DISPLAY INVISIBLE (-675 -5425);
FORCEPROP 0 LAST $SEC 1
J 0
(-675 -5425);
DISPLAY 0.680851 (-675 -5425);
PAINT MONO (-675 -5425);
DISPLAY INVISIBLE (-675 -5425);
FORCEPROP 0 LAST CDS_SEC 1
J 0
(-675 -5425);
DISPLAY 1.021277 (-675 -5425);
DISPLAY INVISIBLE (-675 -5425);
FORCEADD UNIVERSAL_GND..1
(-425 -5975);
FORCEPROP 3 LASTPIN (-425 -5925) SIG_NAME GND\g
J 0
(-415 -5915);
DISPLAY 0.659574 (-415 -5915);
PAINT MONO (-415 -5915);
DISPLAY INVISIBLE (-415 -5915);
FORCEPROP 2 LAST CDS_LIB logical_power
J 0
(-425 -5975);
PAINT MONO (-425 -5975);
DISPLAY INVISIBLE (-425 -5975);
FORCEPROP 1 LAST HDL_POWER GND
J 1
(-400 -6050);
DISPLAY 0.872340 (-400 -6050);
PAINT GREEN (-400 -6050);
DISPLAY INVISIBLE (-400 -6050);
FORCEPROP 1 LAST PATH I55
J 0
(-350 -5975);
DISPLAY 0.872340 (-350 -5975);
PAINT AQUA (-350 -5975);
DISPLAY INVISIBLE (-350 -5975);
FORCEPROP 2 LAST ROOM VR_CORE0_CTRL
J 0
(-697 -5853);
DISPLAY INVISIBLE (-697 -5853);
FORCEADD VCC15..1
(-425 -5200);
FORCEPROP 3 LASTPIN (-425 -5250) SIG_NAME PVCCIN_CPU0\g
J 0
(-415 -5240);
DISPLAY 0.659574 (-415 -5240);
PAINT MONO (-415 -5240);
DISPLAY INVISIBLE (-415 -5240);
FORCEPROP 1 LAST HDL_POWER PVCCIN_CPU0
J 1
(-425 -5150);
DISPLAY 0.617021 (-425 -5150);
PAINT GREEN (-425 -5150);
FORCEPROP 2 LAST CDS_LIB logical_power
J 0
(-425 -5200);
DISPLAY INVISIBLE (-425 -5200);
FORCEPROP 1 LAST PATH I56
J 0
(-375 -5175);
DISPLAY 0.872340 (-375 -5175);
PAINT AQUA (-375 -5175);
DISPLAY INVISIBLE (-375 -5175);
FORCEADD Q_RES..1
(-3100 -3175);
FORCEPROP 1 LAST PART_NUMBER CS00002JB13
J 0
(-3225 -3125);
DISPLAY 0.617021 (-3225 -3125);
PAINT BLUE (-3225 -3125);
DISPLAY INVISIBLE (-3225 -3125);
FORCEPROP 1 LAST WATTAGE 1/16W
J 2
(-2850 -3075);
DISPLAY 0.617021 (-2850 -3075);
PAINT SKYBLUE (-2850 -3075);
FORCEPROP 1 LAST PACK_TYPE 0402LF
J 0
(-3225 -3075);
DISPLAY 0.617021 (-3225 -3075);
PAINT SKYBLUE (-3225 -3075);
FORCEPROP 1 LAST MATERIAL CHIP
J 0
(-2825 -3175);
DISPLAY 0.617021 (-2825 -3175);
PAINT SKYBLUE (-2825 -3175);
FORCEPROP 1 LAST TOLERANCE 5%
J 0
(-2900 -3175);
DISPLAY 0.617021 (-2900 -3175);
PAINT SKYBLUE (-2900 -3175);
FORCEPROP 1 LAST VALUE 0
J 2
(-2925 -3175);
DISPLAY 0.617021 (-2925 -3175);
PAINT SKYBLUE (-2925 -3175);
FORCEPROP 1 LAST LOCATION PR137
J 0
(-3375 -3175);
DISPLAY 0.617021 (-3375 -3175);
PAINT AQUA (-3375 -3175);
FORCEPROP 1 LASTPIN (-3200 -3175) $PN 1
J 0
(-3188 -3163);
DISPLAY 0.617021 (-3188 -3163);
PAINT MONO (-3188 -3163);
FORCEPROP 1 LASTPIN (-3000 -3175) $PN 2
J 0
(-3038 -3163);
DISPLAY 0.617021 (-3038 -3163);
PAINT MONO (-3038 -3163);
FORCEPROP 2 LAST CDS_LIB pure_quanta
J 0
(-3100 -3175);
DISPLAY INVISIBLE (-3100 -3175);
FORCEPROP 1 LAST PATH I57
J 0
(-3150 -3025);
DISPLAY 0.978723 (-3150 -3025);
PAINT WHITE (-3150 -3025);
DISPLAY INVISIBLE (-3150 -3025);
FORCEPROP 0 LAST $SEC 1
J 0
(-2850 -3025);
DISPLAY 0.680851 (-2850 -3025);
PAINT MONO (-2850 -3025);
DISPLAY INVISIBLE (-2850 -3025);
FORCEPROP 0 LAST CDS_SEC 1
J 0
(-2850 -3025);
DISPLAY 1.021277 (-2850 -3025);
DISPLAY INVISIBLE (-2850 -3025);
FORCEADD Q_INDUCTOR4P_14..1
(-3350 -2700);
FORCEPROP 1 LAST PART_NUMBER CV+15^0TZ04
J 0
(-3575 -2540);
DISPLAY 0.617021 (-3575 -2540);
PAINT BLUE (-3575 -2540);
DISPLAY INVISIBLE (-3575 -2540);
FORCEPROP 1 LAST MATERIAL IND
J 0
(-3575 -2490);
DISPLAY 0.617021 (-3575 -2490);
PAINT SKYBLUE (-3575 -2490);
FORCEPROP 2 LAST PART_TYPE SMLF
J 0
(-3575 -2350);
DISPLAY 1.021277 (-3575 -2350);
FORCEPROP 2 LAST VALUE 150NH
J 0
(-3575 -2400);
DISPLAY 0.617021 (-3575 -2400);
PAINT SKYBLUE (-3575 -2400);
FORCEPROP 1 LAST LOCATION PL8
J 0
(-3575 -2445);
DISPLAY 0.617021 (-3575 -2445);
PAINT AQUA (-3575 -2445);
FORCEPROP 2 LASTPIN (-3750 -2575) $PN 1
J 2
(-3760 -2565);
DISPLAY 0.617021 (-3760 -2565);
PAINT MONO (-3760 -2565);
FORCEPROP 2 LASTPIN (-3750 -2825) $PN 2
J 2
(-3760 -2815);
DISPLAY 0.617021 (-3760 -2815);
PAINT MONO (-3760 -2815);
FORCEPROP 2 LASTPIN (-2950 -2825) $PN 3
J 0
(-2940 -2815);
DISPLAY 0.617021 (-2940 -2815);
PAINT MONO (-2940 -2815);
FORCEPROP 2 LASTPIN (-2950 -2575) $PN 4
J 0
(-2940 -2565);
DISPLAY 0.617021 (-2940 -2565);
PAINT MONO (-2940 -2565);
FORCEPROP 2 LAST SEC_TYPE 
J 0
(-3575 -2300);
DISPLAY 1.021277 (-3575 -2300);
DISPLAY INVISIBLE (-3575 -2300);
FORCEPROP 2 LAST CDS_LIB pure_quanta
J 0
(-3350 -2700);
DISPLAY INVISIBLE (-3350 -2700);
FORCEPROP 1 LAST NEEDS_NO_SIZE TRUE
J 0
(-3350 -2700);
DISPLAY 0.468085 (-3350 -2700);
PAINT GREEN (-3350 -2700);
DISPLAY INVISIBLE (-3350 -2700);
FORCEPROP 1 LAST PATH I58
J 0
(-3150 -2545);
DISPLAY 0.723404 (-3150 -2545);
PAINT GREEN (-3150 -2545);
DISPLAY INVISIBLE (-3150 -2545);
FORCEPROP 2 LAST SEC 1
J 0
(-3575 -2300);
DISPLAY 0.680851 (-3575 -2300);
PAINT MONO (-3575 -2300);
DISPLAY INVISIBLE (-3575 -2300);
FORCEADD Q_CAP..1
R 2
(-3625 -2300);
FORCEPROP 1 LAST PART_NUMBER CH4106K1B01
J 2
(-3650 -2425);
DISPLAY 0.617021 (-3650 -2425);
PAINT BLUE (-3650 -2425);
DISPLAY INVISIBLE (-3650 -2425);
FORCEPROP 1 LAST VALUE 100NF
J 2
(-3675 -2225);
DISPLAY 0.617021 (-3675 -2225);
PAINT SKYBLUE (-3675 -2225);
FORCEPROP 1 LAST VOLTAGE 50V
J 2
(-3675 -2275);
DISPLAY 0.617021 (-3675 -2275);
PAINT SKYBLUE (-3675 -2275);
FORCEPROP 1 LAST TOLERANCE 10%
J 2
(-3675 -2325);
DISPLAY 0.617021 (-3675 -2325);
PAINT SKYBLUE (-3675 -2325);
FORCEPROP 1 LAST MATERIAL X7R
J 2
(-3675 -2375);
DISPLAY 0.617021 (-3675 -2375);
PAINT SKYBLUE (-3675 -2375);
FORCEPROP 1 LAST PACK_TYPE C0402
J 2
(-3675 -2475);
DISPLAY 0.617021 (-3675 -2475);
PAINT SKYBLUE (-3675 -2475);
FORCEPROP 1 LAST LOCATION PC235
J 2
(-3675 -2175);
DISPLAY 0.617021 (-3675 -2175);
PAINT AQUA (-3675 -2175);
FORCEPROP 1 LASTPIN (-3625 -2200) $PN 1
J 2
(-3635 -2220);
DISPLAY 0.617021 (-3635 -2220);
FORCEPROP 1 LASTPIN (-3625 -2400) $PN 2
J 2
(-3635 -2420);
DISPLAY 0.617021 (-3635 -2420);
FORCEPROP 2 LAST CDS_LIB pure_quanta
J 2
(-3625 -2300);
PAINT MONO (-3625 -2300);
DISPLAY INVISIBLE (-3625 -2300);
FORCEPROP 1 LAST PATH I59
J 2
(-3675 -2150);
DISPLAY 0.978723 (-3675 -2150);
PAINT WHITE (-3675 -2150);
DISPLAY INVISIBLE (-3675 -2150);
FORCEPROP 2 LAST $SEC 1
J 0
(-3675 -2100);
DISPLAY 0.680851 (-3675 -2100);
PAINT MONO (-3675 -2100);
DISPLAY INVISIBLE (-3675 -2100);
FORCEPROP 2 LAST CDS_SEC 1
J 0
(-3675 -2100);
DISPLAY 1.021277 (-3675 -2100);
DISPLAY INVISIBLE (-3675 -2100);
FORCEADD OFFPAGE..5
(-7075 -5900);
FORCEPROP 2 LAST $XR4 266 
J 0
(-7360 -5828);
DISPLAY 0.638298 (-7360 -5828);
PAINT MONO (-7360 -5828);
FORCEPROP 2 LAST $XR3 270 
J 0
(-7360 -5972);
DISPLAY 0.638298 (-7360 -5972);
PAINT MONO (-7360 -5972);
FORCEPROP 2 LAST $XR2 269 
J 0
(-7360 -5864);
DISPLAY 0.638298 (-7360 -5864);
PAINT MONO (-7360 -5864);
FORCEPROP 2 LAST $XR1 268 
J 0
(-7360 -5936);
DISPLAY 0.638298 (-7360 -5936);
PAINT MONO (-7360 -5936);
FORCEPROP 2 LAST $XR0 267 
J 0
(-7360 -5900);
DISPLAY 0.638298 (-7360 -5900);
PAINT MONO (-7360 -5900);
FORCEPROP 2 LAST CDS_LIB standard
J 0
(-7075 -5900);
DISPLAY INVISIBLE (-7075 -5900);
FORCEPROP 1 LAST OFFPAGE TRUE
J 0
(-6750 -6025);
DISPLAY 0.872340 (-6750 -6025);
PAINT GREEN (-6750 -6025);
DISPLAY INVISIBLE (-6750 -6025);
FORCEPROP 1 LAST COMMENT_BODY TRUE
J 0
(-6975 -5975);
DISPLAY 0.872340 (-6975 -5975);
PAINT GREEN (-6975 -5975);
DISPLAY INVISIBLE (-6975 -5975);
FORCEPROP 2 LAST PATH I6
J 0
(-7350 -5750);
DISPLAY 1.021277 (-7350 -5750);
DISPLAY INVISIBLE (-7350 -5750);
FORCEADD UNIVERSAL_GND..1
(-3000 -2100);
FORCEPROP 3 LASTPIN (-3000 -2050) SIG_NAME GND\g
J 0
(-2990 -2040);
DISPLAY 0.659574 (-2990 -2040);
PAINT MONO (-2990 -2040);
DISPLAY INVISIBLE (-2990 -2040);
FORCEPROP 2 LAST CDS_LIB logical_power
J 0
(-3000 -2100);
PAINT MONO (-3000 -2100);
DISPLAY INVISIBLE (-3000 -2100);
FORCEPROP 1 LAST HDL_POWER GND
J 1
(-2975 -2175);
DISPLAY 0.872340 (-2975 -2175);
PAINT GREEN (-2975 -2175);
DISPLAY INVISIBLE (-2975 -2175);
FORCEPROP 1 LAST PATH I60
J 0
(-2925 -2100);
DISPLAY 0.872340 (-2925 -2100);
PAINT AQUA (-2925 -2100);
DISPLAY INVISIBLE (-2925 -2100);
FORCEPROP 2 LAST ROOM VR_CORE0_CTRL
J 0
(-3272 -1978);
DISPLAY INVISIBLE (-3272 -1978);
FORCEADD OFFPAGE..3
(-2400 -2825);
FORCEPROP 2 LAST $XR0 269 
J 0
(-2186 -2825);
DISPLAY 0.638298 (-2186 -2825);
PAINT MONO (-2186 -2825);
FORCEPROP 2 LAST CDS_LIB standard
J 0
(-2400 -2825);
DISPLAY INVISIBLE (-2400 -2825);
FORCEPROP 1 LAST OFFPAGE TRUE
J 0
(-2075 -2950);
DISPLAY 0.872340 (-2075 -2950);
PAINT GREEN (-2075 -2950);
DISPLAY INVISIBLE (-2075 -2950);
FORCEPROP 1 LAST COMMENT_BODY TRUE
J 0
(-2450 -2925);
DISPLAY 0.872340 (-2450 -2925);
PAINT GREEN (-2450 -2925);
DISPLAY INVISIBLE (-2450 -2925);
FORCEPROP 2 LAST PATH I61
J 0
(-2175 -2775);
DISPLAY 1.021277 (-2175 -2775);
DISPLAY INVISIBLE (-2175 -2775);
FORCEADD Q_CAP..1
(-1825 -2775);
FORCEPROP 1 LAST PART_NUMBER CH5103KEB01
J 0
(-1775 -2950);
DISPLAY 0.617021 (-1775 -2950);
PAINT BLUE (-1775 -2950);
DISPLAY INVISIBLE (-1775 -2950);
FORCEPROP 1 LAST MATERIAL X6S
J 0
(-1775 -2850);
DISPLAY 0.617021 (-1775 -2850);
PAINT SKYBLUE (-1775 -2850);
FORCEPROP 1 LAST PACK_TYPE C0402
J 0
(-1775 -2900);
DISPLAY 0.617021 (-1775 -2900);
PAINT SKYBLUE (-1775 -2900);
FORCEPROP 1 LAST TOLERANCE 10%
J 0
(-1775 -2800);
DISPLAY 0.617021 (-1775 -2800);
PAINT SKYBLUE (-1775 -2800);
FORCEPROP 1 LAST VOLTAGE 16V
J 0
(-1775 -2750);
DISPLAY 0.617021 (-1775 -2750);
PAINT SKYBLUE (-1775 -2750);
FORCEPROP 1 LAST VALUE 1UF
J 0
(-1775 -2700);
DISPLAY 0.617021 (-1775 -2700);
PAINT SKYBLUE (-1775 -2700);
FORCEPROP 1 LAST LOCATION PC243_P0_7
J 0
(-1775 -2650);
DISPLAY 0.617021 (-1775 -2650);
PAINT AQUA (-1775 -2650);
FORCEPROP 1 LASTPIN (-1825 -2675) $PN 1
J 0
(-1815 -2695);
DISPLAY 0.617021 (-1815 -2695);
PAINT MONO (-1815 -2695);
FORCEPROP 1 LASTPIN (-1825 -2875) $PN 2
J 0
(-1815 -2895);
DISPLAY 0.617021 (-1815 -2895);
PAINT MONO (-1815 -2895);
FORCEPROP 2 LAST CDS_LIB pure_quanta
J 0
(-1825 -2775);
DISPLAY INVISIBLE (-1825 -2775);
FORCEPROP 1 LAST PATH I62
J 0
(-1775 -2625);
DISPLAY 0.978723 (-1775 -2625);
PAINT WHITE (-1775 -2625);
DISPLAY INVISIBLE (-1775 -2625);
FORCEPROP 1 LAST LOCATION PC243_P0_7
J 0
(-1775 -2600);
DISPLAY 1.021277 (-1775 -2600);
PAINT AQUA (-1775 -2600);
DISPLAY INVISIBLE (-1775 -2600);
FORCEPROP 0 LAST $SEC 1
J 0
(-1775 -2600);
DISPLAY 0.680851 (-1775 -2600);
PAINT MONO (-1775 -2600);
DISPLAY INVISIBLE (-1775 -2600);
FORCEPROP 0 LAST CDS_SEC 1
J 0
(-1775 -2600);
DISPLAY 1.021277 (-1775 -2600);
DISPLAY INVISIBLE (-1775 -2600);
FORCEADD Q_CAP..1
(-3600 -1675);
FORCEPROP 1 LAST PART_NUMBER CH6223MEA01
J 0
(-3550 -1825);
DISPLAY 0.617021 (-3550 -1825);
PAINT BLUE (-3550 -1825);
DISPLAY INVISIBLE (-3550 -1825);
FORCEPROP 1 LAST MATERIAL X6S
J 0
(-3550 -1725);
DISPLAY 0.617021 (-3550 -1725);
PAINT SKYBLUE (-3550 -1725);
FORCEPROP 1 LAST TOLERANCE 20%
J 0
(-3550 -1675);
DISPLAY 0.617021 (-3550 -1675);
PAINT SKYBLUE (-3550 -1675);
FORCEPROP 1 LAST VALUE 22UF
J 0
(-3550 -1575);
DISPLAY 0.617021 (-3550 -1575);
PAINT SKYBLUE (-3550 -1575);
FORCEPROP 1 LAST VOLTAGE 16V
J 0
(-3550 -1625);
DISPLAY 0.617021 (-3550 -1625);
PAINT SKYBLUE (-3550 -1625);
FORCEPROP 1 LAST PACK_TYPE C0805
J 0
(-3550 -1775);
DISPLAY 0.617021 (-3550 -1775);
PAINT SKYBLUE (-3550 -1775);
FORCEPROP 1 LAST LOCATION PC239_P0_7
J 0
(-3550 -1525);
DISPLAY 0.617021 (-3550 -1525);
PAINT AQUA (-3550 -1525);
FORCEPROP 1 LASTPIN (-3600 -1575) $PN 1
J 0
(-3590 -1595);
DISPLAY 0.617021 (-3590 -1595);
PAINT MONO (-3590 -1595);
FORCEPROP 1 LASTPIN (-3600 -1775) $PN 2
J 0
(-3590 -1795);
DISPLAY 0.617021 (-3590 -1795);
PAINT MONO (-3590 -1795);
FORCEPROP 2 LAST CDS_LIB pure_quanta
J 0
(-3600 -1675);
DISPLAY INVISIBLE (-3600 -1675);
FORCEPROP 1 LAST PATH I63
J 0
(-3550 -1525);
DISPLAY 0.978723 (-3550 -1525);
PAINT WHITE (-3550 -1525);
DISPLAY INVISIBLE (-3550 -1525);
FORCEPROP 1 LAST LOCATION PC239_P0_7
J 0
(-3550 -1475);
DISPLAY 1.021277 (-3550 -1475);
PAINT AQUA (-3550 -1475);
DISPLAY INVISIBLE (-3550 -1475);
FORCEPROP 0 LAST $SEC 1
J 0
(-3550 -1475);
DISPLAY 0.680851 (-3550 -1475);
PAINT MONO (-3550 -1475);
DISPLAY INVISIBLE (-3550 -1475);
FORCEPROP 0 LAST CDS_SEC 1
J 0
(-3550 -1475);
DISPLAY 1.021277 (-3550 -1475);
DISPLAY INVISIBLE (-3550 -1475);
FORCEADD Q_CAP..1
(-3225 -1675);
FORCEPROP 1 LAST PART_NUMBER CH6223MEA01
J 0
(-3175 -1825);
DISPLAY 0.617021 (-3175 -1825);
PAINT BLUE (-3175 -1825);
DISPLAY INVISIBLE (-3175 -1825);
FORCEPROP 1 LAST MATERIAL X6S
J 0
(-3175 -1725);
DISPLAY 0.617021 (-3175 -1725);
PAINT SKYBLUE (-3175 -1725);
FORCEPROP 1 LAST TOLERANCE 20%
J 0
(-3175 -1675);
DISPLAY 0.617021 (-3175 -1675);
PAINT SKYBLUE (-3175 -1675);
FORCEPROP 1 LAST VALUE 22UF
J 0
(-3175 -1575);
DISPLAY 0.617021 (-3175 -1575);
PAINT SKYBLUE (-3175 -1575);
FORCEPROP 1 LAST VOLTAGE 16V
J 0
(-3175 -1625);
DISPLAY 0.617021 (-3175 -1625);
PAINT SKYBLUE (-3175 -1625);
FORCEPROP 1 LAST PACK_TYPE C0805
J 0
(-3175 -1775);
DISPLAY 0.617021 (-3175 -1775);
PAINT SKYBLUE (-3175 -1775);
FORCEPROP 1 LAST LOCATION PC241_P0_7
J 0
(-3175 -1525);
DISPLAY 0.617021 (-3175 -1525);
PAINT AQUA (-3175 -1525);
FORCEPROP 1 LASTPIN (-3225 -1575) $PN 1
J 0
(-3215 -1595);
DISPLAY 0.617021 (-3215 -1595);
PAINT MONO (-3215 -1595);
FORCEPROP 1 LASTPIN (-3225 -1775) $PN 2
J 0
(-3215 -1795);
DISPLAY 0.617021 (-3215 -1795);
PAINT MONO (-3215 -1795);
FORCEPROP 2 LAST CDS_LIB pure_quanta
J 0
(-3225 -1675);
DISPLAY INVISIBLE (-3225 -1675);
FORCEPROP 1 LAST PATH I64
J 0
(-3175 -1525);
DISPLAY 0.978723 (-3175 -1525);
PAINT WHITE (-3175 -1525);
DISPLAY INVISIBLE (-3175 -1525);
FORCEPROP 1 LAST LOCATION PC241_P0_7
J 0
(-3175 -1475);
DISPLAY 1.021277 (-3175 -1475);
PAINT AQUA (-3175 -1475);
DISPLAY INVISIBLE (-3175 -1475);
FORCEPROP 0 LAST $SEC 1
J 0
(-3175 -1475);
DISPLAY 0.680851 (-3175 -1475);
PAINT MONO (-3175 -1475);
DISPLAY INVISIBLE (-3175 -1475);
FORCEPROP 0 LAST CDS_SEC 1
J 0
(-3175 -1475);
DISPLAY 1.021277 (-3175 -1475);
DISPLAY INVISIBLE (-3175 -1475);
FORCEADD VCC15..1
(-3000 -1300);
FORCEPROP 3 LASTPIN (-3000 -1350) SIG_NAME SW_P12V_PVCCIN_CPU0_FLT\g
J 0
(-2990 -1340);
DISPLAY 0.659574 (-2990 -1340);
PAINT MONO (-2990 -1340);
DISPLAY INVISIBLE (-2990 -1340);
FORCEPROP 1 LAST HDL_POWER SW_P12V_PVCCIN_CPU0_FLT
J 1
(-2950 -1250);
DISPLAY 0.617021 (-2950 -1250);
PAINT GREEN (-2950 -1250);
FORCEPROP 2 LAST CDS_LIB logical_power
J 0
(-3000 -1300);
DISPLAY INVISIBLE (-3000 -1300);
FORCEPROP 1 LAST PATH I65
J 0
(-2950 -1275);
DISPLAY 0.872340 (-2950 -1275);
PAINT AQUA (-2950 -1275);
DISPLAY INVISIBLE (-2950 -1275);
FORCEADD Q_CAP..1
(-1400 -2775);
FORCEPROP 1 LAST PART_NUMBER CH622KMEA03
J 0
(-1350 -2950);
DISPLAY 0.617021 (-1350 -2950);
PAINT BLUE (-1350 -2950);
DISPLAY INVISIBLE (-1350 -2950);
FORCEPROP 1 LAST VALUE 22UF
J 0
(-1350 -2700);
DISPLAY 0.617021 (-1350 -2700);
PAINT SKYBLUE (-1350 -2700);
FORCEPROP 1 LAST TOLERANCE 20%
J 0
(-1350 -2800);
DISPLAY 0.617021 (-1350 -2800);
PAINT SKYBLUE (-1350 -2800);
FORCEPROP 1 LAST MATERIAL X6S
J 0
(-1350 -2850);
DISPLAY 0.617021 (-1350 -2850);
PAINT SKYBLUE (-1350 -2850);
FORCEPROP 1 LAST PACK_TYPE C0805
J 0
(-1350 -2900);
DISPLAY 0.617021 (-1350 -2900);
PAINT SKYBLUE (-1350 -2900);
FORCEPROP 1 LAST VOLTAGE 4V
J 0
(-1350 -2750);
DISPLAY 0.617021 (-1350 -2750);
PAINT SKYBLUE (-1350 -2750);
FORCEPROP 1 LAST LOCATION PC245_P0_7
J 0
(-1350 -2650);
DISPLAY 0.617021 (-1350 -2650);
PAINT AQUA (-1350 -2650);
FORCEPROP 1 LASTPIN (-1400 -2675) $PN 1
J 0
(-1390 -2695);
DISPLAY 0.617021 (-1390 -2695);
PAINT MONO (-1390 -2695);
FORCEPROP 1 LASTPIN (-1400 -2875) $PN 2
J 0
(-1390 -2895);
DISPLAY 0.617021 (-1390 -2895);
PAINT MONO (-1390 -2895);
FORCEPROP 2 LAST CDS_LIB pure_quanta
J 0
(-1400 -2775);
DISPLAY INVISIBLE (-1400 -2775);
FORCEPROP 1 LAST PATH I66
J 0
(-1350 -2625);
DISPLAY 0.978723 (-1350 -2625);
PAINT WHITE (-1350 -2625);
DISPLAY INVISIBLE (-1350 -2625);
FORCEPROP 1 LAST LOCATION PC245_P0_7
J 0
(-1350 -2600);
DISPLAY 1.021277 (-1350 -2600);
PAINT AQUA (-1350 -2600);
DISPLAY INVISIBLE (-1350 -2600);
FORCEPROP 0 LAST $SEC 1
J 0
(-1350 -2600);
DISPLAY 0.680851 (-1350 -2600);
PAINT MONO (-1350 -2600);
DISPLAY INVISIBLE (-1350 -2600);
FORCEPROP 0 LAST CDS_SEC 1
J 0
(-1350 -2600);
DISPLAY 1.021277 (-1350 -2600);
DISPLAY INVISIBLE (-1350 -2600);
FORCEADD Q_CAP..1
(-975 -2775);
FORCEPROP 1 LAST PART_NUMBER CH622KMEA03
J 0
(-925 -2950);
DISPLAY 0.617021 (-925 -2950);
PAINT BLUE (-925 -2950);
DISPLAY INVISIBLE (-925 -2950);
FORCEPROP 1 LAST VOLTAGE 4V
J 0
(-925 -2750);
DISPLAY 0.617021 (-925 -2750);
PAINT SKYBLUE (-925 -2750);
FORCEPROP 1 LAST VALUE 22UF
J 0
(-925 -2700);
DISPLAY 0.617021 (-925 -2700);
PAINT SKYBLUE (-925 -2700);
FORCEPROP 1 LAST TOLERANCE 20%
J 0
(-925 -2800);
DISPLAY 0.617021 (-925 -2800);
PAINT SKYBLUE (-925 -2800);
FORCEPROP 1 LAST MATERIAL X6S
J 0
(-925 -2850);
DISPLAY 0.617021 (-925 -2850);
PAINT SKYBLUE (-925 -2850);
FORCEPROP 1 LAST PACK_TYPE C0805
J 0
(-925 -2900);
DISPLAY 0.617021 (-925 -2900);
PAINT SKYBLUE (-925 -2900);
FORCEPROP 1 LAST LOCATION PC247_P0_7
J 0
(-925 -2650);
DISPLAY 0.617021 (-925 -2650);
PAINT AQUA (-925 -2650);
FORCEPROP 1 LASTPIN (-975 -2675) $PN 1
J 0
(-965 -2695);
DISPLAY 0.617021 (-965 -2695);
PAINT MONO (-965 -2695);
FORCEPROP 1 LASTPIN (-975 -2875) $PN 2
J 0
(-965 -2895);
DISPLAY 0.617021 (-965 -2895);
PAINT MONO (-965 -2895);
FORCEPROP 2 LAST CDS_LIB pure_quanta
J 0
(-975 -2775);
DISPLAY INVISIBLE (-975 -2775);
FORCEPROP 1 LAST PATH I67
J 0
(-925 -2625);
DISPLAY 0.978723 (-925 -2625);
PAINT WHITE (-925 -2625);
DISPLAY INVISIBLE (-925 -2625);
FORCEPROP 1 LAST LOCATION PC247_P0_7
J 0
(-925 -2600);
DISPLAY 1.021277 (-925 -2600);
PAINT AQUA (-925 -2600);
DISPLAY INVISIBLE (-925 -2600);
FORCEPROP 0 LAST $SEC 1
J 0
(-925 -2600);
DISPLAY 0.680851 (-925 -2600);
PAINT MONO (-925 -2600);
DISPLAY INVISIBLE (-925 -2600);
FORCEPROP 0 LAST CDS_SEC 1
J 0
(-925 -2600);
DISPLAY 1.021277 (-925 -2600);
DISPLAY INVISIBLE (-925 -2600);
FORCEADD UNIVERSAL_GND..1
(-675 -3150);
FORCEPROP 3 LASTPIN (-675 -3100) SIG_NAME GND\g
J 0
(-665 -3090);
DISPLAY 0.659574 (-665 -3090);
PAINT MONO (-665 -3090);
DISPLAY INVISIBLE (-665 -3090);
FORCEPROP 2 LAST CDS_LIB logical_power
J 0
(-675 -3150);
PAINT MONO (-675 -3150);
DISPLAY INVISIBLE (-675 -3150);
FORCEPROP 1 LAST HDL_POWER GND
J 1
(-650 -3225);
DISPLAY 0.872340 (-650 -3225);
PAINT GREEN (-650 -3225);
DISPLAY INVISIBLE (-650 -3225);
FORCEPROP 1 LAST PATH I68
J 0
(-600 -3150);
DISPLAY 0.872340 (-600 -3150);
PAINT AQUA (-600 -3150);
DISPLAY INVISIBLE (-600 -3150);
FORCEPROP 2 LAST ROOM VR_CORE0_CTRL
J 0
(-947 -3028);
DISPLAY INVISIBLE (-947 -3028);
FORCEADD VCC15..1
(-675 -2375);
FORCEPROP 3 LASTPIN (-675 -2425) SIG_NAME PVCCIN_CPU0\g
J 0
(-665 -2415);
DISPLAY 0.659574 (-665 -2415);
PAINT MONO (-665 -2415);
DISPLAY INVISIBLE (-665 -2415);
FORCEPROP 1 LAST HDL_POWER PVCCIN_CPU0
J 1
(-675 -2325);
DISPLAY 0.617021 (-675 -2325);
PAINT GREEN (-675 -2325);
FORCEPROP 2 LAST CDS_LIB logical_power
J 0
(-675 -2375);
DISPLAY INVISIBLE (-675 -2375);
FORCEPROP 1 LAST PATH I69
J 0
(-625 -2350);
DISPLAY 0.872340 (-625 -2350);
PAINT AQUA (-625 -2350);
DISPLAY INVISIBLE (-625 -2350);
FORCEADD Q_CAP..2
(-7025 -5600);
FORCEPROP 1 LAST PART_NUMBER CH4104K1B00
J 1
(-6750 -5550);
DISPLAY 0.617021 (-6750 -5550);
PAINT BLUE (-6750 -5550);
DISPLAY INVISIBLE (-6750 -5550);
FORCEPROP 1 LAST VALUE 0.1UF
J 2
(-6725 -5600);
DISPLAY 0.617021 (-6725 -5600);
PAINT SKYBLUE (-6725 -5600);
FORCEPROP 1 LAST VOLTAGE 25V
J 0
(-6700 -5600);
DISPLAY 0.617021 (-6700 -5600);
PAINT SKYBLUE (-6700 -5600);
FORCEPROP 1 LAST TOLERANCE 10%
J 2
(-6500 -5550);
DISPLAY 0.617021 (-6500 -5550);
PAINT SKYBLUE (-6500 -5550);
FORCEPROP 1 LAST MATERIAL X7R
J 0
(-6450 -5600);
DISPLAY 0.617021 (-6450 -5600);
PAINT SKYBLUE (-6450 -5600);
FORCEPROP 1 LAST PACK_TYPE 0402
J 1
(-6525 -5600);
DISPLAY 0.617021 (-6525 -5600);
PAINT SKYBLUE (-6525 -5600);
FORCEPROP 1 LAST LOCATION PC1344
J 1
(-7225 -5600);
DISPLAY 0.617021 (-7225 -5600);
PAINT AQUA (-7225 -5600);
FORCEPROP 1 LASTPIN (-7125 -5600) $PN 1
J 0
(-7135 -5585);
DISPLAY 0.617021 (-7135 -5585);
FORCEPROP 1 LASTPIN (-6925 -5600) $PN 2
J 0
(-6940 -5585);
DISPLAY 0.617021 (-6940 -5585);
FORCEPROP 2 LAST CDS_LIB pure_quanta
J 0
(-7025 -5600);
PAINT MONO (-7025 -5600);
DISPLAY INVISIBLE (-7025 -5600);
FORCEPROP 1 LAST PATH I7
J 0
(-7025 -5400);
DISPLAY 0.978723 (-7025 -5400);
PAINT WHITE (-7025 -5400);
DISPLAY INVISIBLE (-7025 -5400);
FORCEPROP 2 LAST $SEC 1
J 0
(-7025 -5350);
DISPLAY 0.680851 (-7025 -5350);
PAINT MONO (-7025 -5350);
DISPLAY INVISIBLE (-7025 -5350);
FORCEPROP 2 LAST CDS_SEC 1
J 0
(-7025 -5350);
DISPLAY 1.021277 (-7025 -5350);
DISPLAY INVISIBLE (-7025 -5350);
FORCEADD OFFPAGE..1
(-7075 -5500);
FORCEPROP 2 LAST $XR6 272 
J 0
(-8047 -5500);
DISPLAY 0.638298 (-8047 -5500);
PAINT MONO (-8047 -5500);
FORCEPROP 2 LAST $XR5 271 
J 0
(-7927 -5500);
DISPLAY 0.638298 (-7927 -5500);
PAINT MONO (-7927 -5500);
FORCEPROP 2 LAST $XR4 270 
J 0
(-7807 -5500);
DISPLAY 0.638298 (-7807 -5500);
PAINT MONO (-7807 -5500);
FORCEPROP 2 LAST $XR3 269 
J 0
(-7687 -5500);
DISPLAY 0.638298 (-7687 -5500);
PAINT MONO (-7687 -5500);
FORCEPROP 2 LAST $XR2 268 
J 0
(-7567 -5500);
DISPLAY 0.638298 (-7567 -5500);
PAINT MONO (-7567 -5500);
FORCEPROP 2 LAST $XR1 267 
J 0
(-7447 -5500);
DISPLAY 0.638298 (-7447 -5500);
PAINT MONO (-7447 -5500);
FORCEPROP 2 LAST $XR0 266 
J 0
(-7327 -5500);
DISPLAY 0.638298 (-7327 -5500);
PAINT MONO (-7327 -5500);
FORCEPROP 2 LAST CDS_LIB standard
J 0
(-7075 -5500);
DISPLAY INVISIBLE (-7075 -5500);
FORCEPROP 1 LAST OFFPAGE TRUE
J 0
(-6750 -5625);
DISPLAY 0.872340 (-6750 -5625);
PAINT GREEN (-6750 -5625);
DISPLAY INVISIBLE (-6750 -5625);
FORCEPROP 1 LAST COMMENT_BODY TRUE
J 0
(-6950 -5600);
DISPLAY 0.872340 (-6950 -5600);
PAINT GREEN (-6950 -5600);
DISPLAY INVISIBLE (-6950 -5600);
FORCEPROP 2 LAST PATH I8
J 0
(-7325 -5450);
DISPLAY 1.021277 (-7325 -5450);
DISPLAY INVISIBLE (-7325 -5450);
FORCEADD OFFPAGE..5
(-7075 -5400);
FORCEPROP 2 LAST $XR0 266 
J 0
(-7360 -5400);
DISPLAY 0.638298 (-7360 -5400);
PAINT MONO (-7360 -5400);
FORCEPROP 2 LAST CDS_LIB standard
J 0
(-7075 -5400);
DISPLAY INVISIBLE (-7075 -5400);
FORCEPROP 1 LAST OFFPAGE TRUE
J 0
(-6750 -5525);
DISPLAY 0.872340 (-6750 -5525);
PAINT GREEN (-6750 -5525);
DISPLAY INVISIBLE (-6750 -5525);
FORCEPROP 1 LAST COMMENT_BODY TRUE
J 0
(-6975 -5475);
DISPLAY 0.872340 (-6975 -5475);
PAINT GREEN (-6975 -5475);
DISPLAY INVISIBLE (-6975 -5475);
FORCEPROP 2 LAST PATH I9
J 0
(-7350 -5350);
DISPLAY 1.021277 (-7350 -5350);
DISPLAY INVISIBLE (-7350 -5350);
FORCEADD DNS..1
(-7525 -3100);
PAINT RED (-7525 -3100);
FORCEPROP 2 LAST CDS_LIB mstr_misc
J 0
(-7525 -3100);
PAINT MONO (-7525 -3100);
DISPLAY INVISIBLE (-7525 -3100);
FORCEPROP 1 LAST COMMENT_BODY TRUE
R 1
J 0
(-7450 -3325);
DISPLAY 0.872340 (-7450 -3325);
PAINT GREEN (-7450 -3325);
DISPLAY INVISIBLE (-7450 -3325);
FORCEADD DNS..1
(-7550 -5925);
PAINT RED (-7550 -5925);
FORCEPROP 2 LAST CDS_LIB mstr_misc
J 0
(-7550 -5925);
PAINT MONO (-7550 -5925);
DISPLAY INVISIBLE (-7550 -5925);
FORCEPROP 1 LAST COMMENT_BODY TRUE
R 1
J 0
(-7475 -6150);
DISPLAY 0.872340 (-7475 -6150);
PAINT GREEN (-7475 -6150);
DISPLAY INVISIBLE (-7475 -6150);
FORCEADD QUANTA_TITLE_BLOCK_C..1
(0 -7125);
FORCEPROP 0 LAST CDS_CON_LAST_MODIFIED Fri Aug 25 14:04:41 2023
J 0
(-1885 -7110);
DISPLAY INVISIBLE (-1885 -7110);
FORCEPROP 1 LAST CUSTOM_TXT_CDS <CON_LAST_MODIFIED>
J 0
(-1885 -7110);
DISPLAY 0.978723 (-1885 -7110);
FORCEPROP 2 LAST CUSTOM_TXT_CDS <XR_PAGE_TITLE>
J 0
(-7890 -1875);
DISPLAY 0.638298 (-7890 -1875);
PAINT PINK (-7890 -1875);
DISPLAY INVISIBLE (-7890 -1875);
FORCEPROP 1 LAST CUSTOM_TXT_CDS <NAME_2>
J 0
(-3175 -7075);
FORCEPROP 1 LAST CUSTOM_TXT_CDS <NAME_1>
J 0
(-3175 -6950);
FORCEPROP 1 LAST CUSTOM_TXT_CDS <Q_NUMBER>
J 0
(-1403 -7022);
DISPLAY 1.212766 (-1403 -7022);
FORCEPROP 1 LAST CUSTOM_TXT_CDS <Q_PROJ>
J 0
(-2382 -7023);
DISPLAY 1.212766 (-2382 -7023);
FORCEPROP 1 LAST CUSTOM_TXT_CDS <Q_REV>
J 0
(-184 -7022);
DISPLAY 1.212766 (-184 -7022);
FORCEPROP 1 LAST CUSTOM_TXT_CDS <CON_PAGE_NUM> OF <CON_TOTAL_PAGES>
J 0
(-446 -7107);
DISPLAY 0.978723 (-446 -7107);
FORCEPROP 1 LAST Q_TITLE VCCIN CPU0 VR PHASE 7&8 (5/7)
J 0
(-9300 -7050);
DISPLAY 2.446809 (-9300 -7050);
PAINT GREEN (-9300 -7050);
FORCEPROP 1 LAST Q_DEPT 
J 1
(-3763 -7076);
DISPLAY 1.957447 (-3763 -7076);
PAINT GREEN (-3763 -7076);
FORCEPROP 2 LAST CDS_XR_PAGE_TITLE CR-270 : @S9S_MB_2U_LIB.S9S_MB_2U(SCH_1):PAGE270
J 0
(-7890 -1875);
DISPLAY 0.638298 (-7890 -1875);
PAINT PINK (-7890 -1875);
DISPLAY INVISIBLE (-7890 -1875);
FORCEPROP 1 LAST COMMENT_BODY TRUE
J 0
(12 -7138);
DISPLAY 0.978723 (12 -7138);
PAINT GREEN (12 -7138);
DISPLAY INVISIBLE (12 -7138);
FORCEPROP 2 LAST CDS_LIB pure_quanta
J 0
(0 -7125);
DISPLAY INVISIBLE (0 -7125);
FORCEPROP 1 LAST CDS_LMAN_SYM_OUTLINE -9475,6775,100,-125
J 0
(0 -7125);
DISPLAY 0.468085 (0 -7125);
PAINT GREEN (0 -7125);
DISPLAY INVISIBLE (0 -7125);
FORCEPROP 2 LAST PAGE_BORDER TRUE
J 0
(-7890 -1875);
DISPLAY 0.638298 (-7890 -1875);
PAINT PINK (-7890 -1875);
DISPLAY INVISIBLE (-7890 -1875);
WIRE 16 -1 (-675 -2425)(-675 -2575);
WIRE 16 -1 (-3000 -1350)(-3000 -1425);
WIRE 16 -1 (-425 -5250)(-425 -5400);
WIRE 16 -1 (-3025 -4175)(-3025 -4250);
WIRE 16 -1 (-7125 -1350)(-7125 -1300);
WIRE 16 -1 (-6700 -1350)(-7125 -1350);
WIRE 16 -1 (-7125 -1475)(-7125 -1350);
WIRE 16 -1 (-7150 -4175)(-7150 -4125);
WIRE 16 -1 (-6725 -4175)(-7150 -4175);
WIRE 16 -1 (-7150 -4300)(-7150 -4175);
WIRE 16 -1 (-675 -3100)(-675 -3000);
WIRE 16 -1 (-3000 -2050)(-3000 -1925);
WIRE 16 -1 (-425 -5925)(-425 -5825);
WIRE 16 -1 (-2475 -5650)(-2475 -5700);
WIRE 16 -1 (-2775 -5650)(-2475 -5650);
WIRE 16 -1 (-3025 -4875)(-3025 -4750);
WIRE 16 -1 (-4550 -2825)(-4550 -2875);
WIRE 16 -1 (-4425 -2825)(-4550 -2825);
WIRE 16 -1 (-4950 -3175)(-4950 -3250);
WIRE 16 -1 (-4950 -3125)(-4950 -3175);
WIRE 16 -1 (-5200 -3175)(-4950 -3175);
WIRE 16 -1 (-6700 -1675)(-6700 -1750);
WIRE 16 -1 (-7125 -2175)(-7125 -2275);
WIRE 16 -1 (-7625 -2775)(-7625 -2800);
WIRE 16 -1 (-7625 -2775)(-7050 -2775);
WIRE 16 -1 (-7525 -3175)(-7525 -3250);
WIRE 16 -1 (-4975 -6000)(-4975 -6075);
WIRE 16 -1 (-4975 -5950)(-4975 -6000);
WIRE 16 -1 (-5225 -6000)(-4975 -6000);
WIRE 16 -1 (-6725 -4500)(-6725 -4575);
WIRE 16 -1 (-7150 -5000)(-7150 -5100);
WIRE 16 -1 (-7650 -5600)(-7650 -5625);
WIRE 16 -1 (-7650 -5600)(-7125 -5600);
WIRE 16 -1 (-7550 -6000)(-7550 -6075);
WIRE 16 -1 (-6075 -5400)(-7025 -5400);
FORCEPROP 2 LAST SIG_NAME PVCCIN_CPU0_IMON8
J 0
(-6910 -5390);
DISPLAY 0.617021 (-6910 -5390);
WIRE 16 -1 (-6175 -5600)(-6925 -5600);
WIRE 16 -1 (-7025 -5500)(-6175 -5500);
FORCEPROP 2 LAST SIG_NAME PVCCIN_CPU0_VREF
J 0
(-6910 -5490);
DISPLAY 0.617021 (-6910 -5490);
WIRE 16 -1 (-6175 -5500)(-6175 -5600);
FORCEPROP 0 LAST CDS_PHYS_NET_NAME PVCCIN_CPU0_VREF
J 0
(-6175 -5575);
PAINT MONO (-6175 -5575);
DISPLAY INVISIBLE (-6175 -5575);
WIRE 16 -1 (-6175 -5500)(-6075 -5500);
WIRE 16 -1 (-7150 -4650)(-7150 -4800);
WIRE 16 -1 (-7150 -4500)(-7150 -4650);
WIRE 16 -1 (-7150 -4650)(-6750 -4650);
WIRE 16 -1 (-6750 -5050)(-6750 -4650);
WIRE 16 -1 (-6175 -5050)(-6750 -5050);
FORCEPROP 2 LAST SIG_NAME PVCCIN_CPU0_VDD8
J 0
(-6710 -5040);
DISPLAY 0.617021 (-6710 -5040);
WIRE 16 -1 (-6075 -5050)(-6175 -5050);
WIRE 16 -1 (-6175 -5250)(-6175 -5050);
WIRE 16 -1 (-6075 -5250)(-6175 -5250);
WIRE 16 -1 (-5075 -4950)(-4475 -4950);
WIRE 16 -1 (-5075 -5050)(-5075 -4950);
FORCEPROP 2 LAST SIG_NAME SW_PVCCIN_CPU0_BOOT8
J 0
(-5285 -4940);
DISPLAY 0.617021 (-5285 -4940);
WIRE 16 -1 (-5225 -5050)(-5075 -5050);
WIRE 16 -1 (-3650 -4950)(-3650 -5025);
WIRE 16 -1 (-4275 -4950)(-3650 -4950);
FORCEPROP 2 LAST SIG_NAME SW_PVCCIN_CPU0_BOOT8_R
J 0
(-3985 -4940);
DISPLAY 0.617021 (-3985 -4940);
WIRE 16 -1 (-3250 -4600)(-3250 -4750);
WIRE 16 -1 (-3025 -4750)(-3250 -4750);
WIRE 16 -1 (-3625 -4600)(-3625 -4750);
WIRE 16 -1 (-3625 -4750)(-3250 -4750);
WIRE 16 -1 (-4025 -4750)(-3625 -4750);
WIRE 16 -1 (-4025 -4600)(-4025 -4750);
WIRE 16 -1 (-4425 -4600)(-4425 -4750);
WIRE 16 -1 (-4025 -4750)(-4425 -4750);
WIRE 16 -1 (-4825 -4750)(-4425 -4750);
WIRE 16 -1 (-4825 -4600)(-4825 -4750);
WIRE 16 -1 (-5225 -4800)(-5050 -4800);
WIRE 16 -1 (-5225 -4750)(-5050 -4750);
WIRE 16 -1 (-5050 -4800)(-5050 -4750);
WIRE 16 -1 (-5050 -4250)(-5050 -4750);
WIRE 16 -1 (-5050 -4250)(-4825 -4250);
WIRE 16 -1 (-4825 -4400)(-4825 -4250);
WIRE 16 -1 (-4825 -4250)(-4425 -4250);
WIRE 16 -1 (-4425 -4400)(-4425 -4250);
WIRE 16 -1 (-4425 -4250)(-4025 -4250);
WIRE 16 -1 (-4025 -4250)(-4025 -4400);
WIRE 16 -1 (-4025 -4250)(-3625 -4250);
WIRE 16 -1 (-3625 -4400)(-3625 -4250);
WIRE 16 -1 (-3625 -4250)(-3250 -4250);
WIRE 16 -1 (-3250 -4400)(-3250 -4250);
WIRE 16 -1 (-3025 -4250)(-3250 -4250);
WIRE 16 -1 (-4225 -2825)(-3750 -2825);
FORCEPROP 2 LAST SIG_NAME IND_P0_CPL7
J 0
(-4160 -2815);
DISPLAY 0.617021 (-4160 -2815);
WIRE 16 -1 (-4250 -2125)(-3625 -2125);
FORCEPROP 2 LAST SIG_NAME SW_PVCCIN_CPU0_BOOT7_R
J 0
(-3935 -2115);
DISPLAY 0.617021 (-3935 -2115);
WIRE 16 -1 (-3625 -2125)(-3625 -2200);
WIRE 16 -1 (-4800 -1775)(-4800 -1925);
WIRE 16 -1 (-4800 -1925)(-4400 -1925);
WIRE 16 -1 (-4400 -1775)(-4400 -1925);
WIRE 16 -1 (-4000 -1925)(-4400 -1925);
WIRE 16 -1 (-4000 -1775)(-4000 -1925);
WIRE 16 -1 (-4000 -1925)(-3600 -1925);
WIRE 16 -1 (-3600 -1775)(-3600 -1925);
WIRE 16 -1 (-3600 -1925)(-3225 -1925);
WIRE 16 -1 (-3225 -1775)(-3225 -1925);
WIRE 16 -1 (-3000 -1925)(-3225 -1925);
WIRE 16 -1 (-5200 -1975)(-5025 -1975);
WIRE 16 -1 (-5200 -1925)(-5025 -1925);
WIRE 16 -1 (-5025 -1975)(-5025 -1925);
WIRE 16 -1 (-5025 -1425)(-5025 -1925);
WIRE 16 -1 (-4800 -1575)(-4800 -1425);
WIRE 16 -1 (-5025 -1425)(-4800 -1425);
WIRE 16 -1 (-4800 -1425)(-4400 -1425);
WIRE 16 -1 (-4400 -1575)(-4400 -1425);
WIRE 16 -1 (-4400 -1425)(-4000 -1425);
WIRE 16 -1 (-4000 -1425)(-4000 -1575);
WIRE 16 -1 (-3600 -1575)(-3600 -1425);
WIRE 16 -1 (-4000 -1425)(-3600 -1425);
WIRE 16 -1 (-3600 -1425)(-3225 -1425);
WIRE 16 -1 (-3225 -1575)(-3225 -1425);
WIRE 16 -1 (-3000 -1425)(-3225 -1425);
WIRE 16 -1 (-5200 -2225)(-5050 -2225);
WIRE 16 -1 (-5050 -2225)(-5050 -2125);
FORCEPROP 2 LAST SIG_NAME SW_PVCCIN_CPU0_BOOT7
J 0
(-5235 -2115);
DISPLAY 0.617021 (-5235 -2115);
WIRE 16 -1 (-5050 -2125)(-4450 -2125);
WIRE 16 -1 (-3625 -2475)(-3625 -2400);
WIRE 16 -1 (-5200 -2475)(-3625 -2475);
FORCEPROP 2 LAST SIG_NAME SW_PVCCIN_CPU0_BOOTR7
J 0
(-5010 -2465);
DISPLAY 0.617021 (-5010 -2465);
WIRE 16 -1 (-5200 -2575)(-3750 -2575);
FORCEPROP 2 LAST SIG_NAME SW_PVCCIN_CPU0_SW7
J 0
(-5010 -2565);
DISPLAY 0.617021 (-5010 -2565);
WIRE 16 -1 (-5200 -3125)(-4950 -3125);
WIRE 16 -1 (-5200 -3075)(-4950 -3075);
WIRE 16 -1 (-4950 -3075)(-4950 -3125);
WIRE 16 -1 (-4950 -3025)(-4950 -3075);
WIRE 16 -1 (-5200 -3025)(-4950 -3025);
WIRE 16 -1 (-975 -2675)(-975 -2575);
WIRE 16 -1 (-675 -2575)(-975 -2575);
WIRE 16 -1 (-1400 -2575)(-1400 -2675);
WIRE 16 -1 (-1400 -2575)(-975 -2575);
WIRE 16 -1 (-1825 -2675)(-1825 -2575);
WIRE 16 -1 (-1825 -2575)(-1400 -2575);
WIRE 16 -1 (-2950 -2575)(-1925 -2575);
WIRE 16 -1 (-1825 -2575)(-1925 -2575);
WIRE 16 -1 (-1925 -3175)(-1925 -2575);
WIRE 16 -1 (-3000 -3175)(-1925 -3175);
WIRE 16 -1 (-6700 -1350)(-6700 -1475);
WIRE 16 -1 (-6125 -1350)(-6700 -1350);
WIRE 16 -1 (-6125 -1925)(-6125 -1350);
WIRE 16 -1 (-6050 -1925)(-6125 -1925);
WIRE 16 -1 (-6050 -2425)(-6150 -2425);
WIRE 16 -1 (-6150 -2425)(-6150 -2225);
WIRE 16 -1 (-6150 -2225)(-6050 -2225);
WIRE 16 -1 (-6725 -2225)(-6150 -2225);
FORCEPROP 2 LAST SIG_NAME PVCCIN_CPU0_VDD7
J 0
(-6685 -2215);
DISPLAY 0.617021 (-6685 -2215);
WIRE 16 -1 (-6725 -2225)(-6725 -1825);
WIRE 16 -1 (-7125 -1825)(-7125 -1975);
WIRE 16 -1 (-7125 -1675)(-7125 -1825);
WIRE 16 -1 (-7125 -1825)(-6725 -1825);
WIRE 16 -1 (-7525 -2875)(-7525 -2975);
WIRE 16 -1 (-7525 -2875)(-6050 -2875);
FORCEPROP 2 LAST SIG_NAME PVCCIN_CPU0_LSET7
J 0
(-6885 -2865);
DISPLAY 0.617021 (-6885 -2865);
WIRE 16 -1 (-6150 -2775)(-6850 -2775);
WIRE 16 -1 (-7000 -2675)(-6150 -2675);
FORCEPROP 2 LAST SIG_NAME PVCCIN_CPU0_VREF
J 0
(-6885 -2665);
DISPLAY 0.617021 (-6885 -2665);
WIRE 16 -1 (-6150 -2675)(-6150 -2775);
FORCEPROP 0 LAST CDS_PHYS_NET_NAME PVCCIN_CPU0_VREF
J 0
(-6150 -2750);
PAINT MONO (-6150 -2750);
DISPLAY INVISIBLE (-6150 -2750);
WIRE 16 -1 (-6150 -2675)(-6050 -2675);
WIRE 16 -1 (-6050 -3075)(-7000 -3075);
FORCEPROP 2 LAST SIG_NAME PVCCIN_CPU0_ATSEN
J 0
(-6885 -3065);
DISPLAY 0.617021 (-6885 -3065);
WIRE 16 -1 (-6050 -2575)(-7000 -2575);
FORCEPROP 2 LAST SIG_NAME PVCCIN_CPU0_IMON7
J 0
(-6885 -2565);
DISPLAY 0.617021 (-6885 -2565);
WIRE 16 -1 (-4800 -3175)(-3200 -3175);
FORCEPROP 2 LAST SIG_NAME PVCCIN_CPU0_VOS7
J 0
(-4660 -3165);
DISPLAY 0.617021 (-4660 -3165);
WIRE 16 -1 (-4800 -2825)(-4800 -3175);
WIRE 16 -1 (-5200 -2825)(-4800 -2825);
WIRE 16 -1 (-6725 -4175)(-6725 -4300);
WIRE 16 -1 (-6150 -4175)(-6725 -4175);
WIRE 16 -1 (-6150 -4750)(-6150 -4175);
WIRE 16 -1 (-6075 -4750)(-6150 -4750);
WIRE 16 -1 (-5225 -5850)(-4975 -5850);
WIRE 16 -1 (-5225 -5900)(-4975 -5900);
WIRE 16 -1 (-4975 -5850)(-4975 -5900);
WIRE 16 -1 (-4975 -5900)(-4975 -5950);
WIRE 16 -1 (-5225 -5950)(-4975 -5950);
WIRE 16 -1 (-1575 -5700)(-1575 -5825);
WIRE 16 -1 (-1575 -5825)(-1150 -5825);
WIRE 16 -1 (-1150 -5825)(-1150 -5700);
WIRE 16 -1 (-725 -5825)(-1150 -5825);
WIRE 16 -1 (-725 -5825)(-725 -5700);
WIRE 16 -1 (-425 -5825)(-725 -5825);
WIRE 16 -1 (-1825 -5900)(-3050 -5900);
WIRE 16 -1 (-2775 -5400)(-1825 -5400);
WIRE 16 -1 (-1825 -5400)(-1825 -5900);
WIRE 16 -1 (-1575 -5400)(-1825 -5400);
WIRE 16 -1 (-1575 -5500)(-1575 -5400);
WIRE 16 -1 (-1575 -5400)(-1150 -5400);
WIRE 16 -1 (-1150 -5400)(-1150 -5500);
WIRE 16 -1 (-1150 -5400)(-725 -5400);
WIRE 16 -1 (-725 -5400)(-725 -5500);
WIRE 16 -1 (-725 -5400)(-425 -5400);
WIRE 16 -1 (-1825 -2875)(-1825 -3000);
WIRE 16 -1 (-1825 -3000)(-1400 -3000);
WIRE 16 -1 (-1400 -3000)(-1400 -2875);
WIRE 16 -1 (-975 -3000)(-1400 -3000);
WIRE 16 -1 (-975 -2875)(-975 -3000);
WIRE 16 -1 (-675 -3000)(-975 -3000);
WIRE 16 -1 (-2950 -2825)(-2450 -2825);
FORCEPROP 2 LAST SIG_NAME IND_P0_CPL6
J 0
(-2810 -2815);
DISPLAY 0.489362 (-2810 -2815);
WIRE 16 -1 (-3650 -5300)(-3650 -5225);
WIRE 16 -1 (-5225 -5300)(-3650 -5300);
FORCEPROP 2 LAST SIG_NAME SW_PVCCIN_CPU0_BOOTR8
J 0
(-5035 -5290);
DISPLAY 0.617021 (-5035 -5290);
WIRE 16 -1 (-5225 -5400)(-3575 -5400);
FORCEPROP 2 LAST SIG_NAME SW_PVCCIN_CPU0_SW8
J 0
(-5035 -5390);
DISPLAY 0.617021 (-5035 -5390);
WIRE 16 -1 (-4050 -5650)(-3575 -5650);
FORCEPROP 2 LAST SIG_NAME IND_P0_CPL8
J 0
(-3985 -5640);
DISPLAY 0.617021 (-3985 -5640);
WIRE 16 -1 (-6050 -3175)(-7000 -3175);
FORCEPROP 2 LAST SIG_NAME PVCCIN_CPU0_PWM7
J 0
(-6885 -3165);
DISPLAY 0.617021 (-6885 -3165);
WIRE 16 -1 (-5225 -5650)(-4875 -5650);
WIRE 16 -1 (-4875 -5650)(-4875 -5900);
WIRE 16 -1 (-4875 -5900)(-3250 -5900);
FORCEPROP 2 LAST SIG_NAME PVCCIN_CPU0_VOS8
J 0
(-4710 -5890);
DISPLAY 0.617021 (-4710 -5890);
WIRE 16 -1 (-6075 -6000)(-7025 -6000);
FORCEPROP 2 LAST SIG_NAME PVCCIN_CPU0_PWM8
J 0
(-6910 -5990);
DISPLAY 0.617021 (-6910 -5990);
WIRE 16 -1 (-6075 -5900)(-7025 -5900);
FORCEPROP 2 LAST SIG_NAME PVCCIN_CPU0_ATSEN
J 0
(-6910 -5890);
DISPLAY 0.617021 (-6910 -5890);
WIRE 16 -1 (-7550 -5700)(-7550 -5800);
WIRE 16 -1 (-7550 -5700)(-6075 -5700);
FORCEPROP 2 LAST SIG_NAME PVCCIN_CPU0_LSET8
J 0
(-6910 -5690);
DISPLAY 0.617021 (-6910 -5690);
DOT 1 (-3600 -1925);
DOT 1 (-3600 -1425);
DOT 1 (-6150 -2675);
DOT 1 (-7150 -4650);
DOT 1 (-7150 -4175);
DOT 1 (-6175 -5500);
DOT 1 (-6175 -5050);
DOT 1 (-6725 -4175);
DOT 1 (-4975 -5950);
DOT 1 (-4975 -6000);
DOT 1 (-4975 -5900);
DOT 1 (-5050 -4750);
DOT 1 (-4825 -4250);
DOT 1 (-4425 -4750);
DOT 1 (-4425 -4250);
DOT 1 (-4025 -4750);
DOT 1 (-4025 -4250);
DOT 1 (-6150 -2225);
DOT 1 (-7125 -1825);
DOT 1 (-7125 -1350);
DOT 1 (-6700 -1350);
DOT 1 (-4950 -3175);
DOT 1 (-4950 -3125);
DOT 1 (-4950 -3075);
DOT 1 (-5025 -1925);
DOT 1 (-4800 -1425);
DOT 1 (-4400 -1925);
DOT 1 (-4400 -1425);
DOT 1 (-4000 -1925);
DOT 1 (-4000 -1425);
DOT 1 (-3625 -4750);
DOT 1 (-3625 -4250);
DOT 1 (-3250 -4750);
DOT 1 (-3250 -4250);
DOT 1 (-1825 -5400);
DOT 1 (-1575 -5400);
DOT 1 (-1150 -5825);
DOT 1 (-725 -5825);
DOT 1 (-1150 -5400);
DOT 1 (-725 -5400);
DOT 1 (-1925 -2575);
DOT 1 (-1825 -2575);
DOT 1 (-3225 -1925);
DOT 1 (-3225 -1425);
DOT 1 (-1400 -3000);
DOT 1 (-975 -3000);
DOT 1 (-1400 -2575);
DOT 1 (-975 -2575);
FORCENOTE
DCR=0.17M OHM
(-4350 -3125) 0;
DISPLAY LEFT (-4350 -3125);
DISPLAY 1.021277 (-4350 -3125);
FORCENOTE
ISAT=60A@100C
(-4350 -3050) 0;
DISPLAY LEFT (-4350 -3050);
DISPLAY 1.021277 (-4350 -3050);
FORCENOTE
6.5*6.5*10.0
(-4350 -2975) 0;
DISPLAY LEFT (-4350 -2975);
DISPLAY 1.021277 (-4350 -2975);
FORCENOTE
PGL6312.121AHLT 
(-4350 -2900) 0;
DISPLAY LEFT (-4350 -2900);
DISPLAY 1.021277 (-4350 -2900);
FORCENOTE
PVCCIN_CPU0_PHASE8
(-6000 -4225) 0;
DISPLAY LEFT (-6000 -4225);
DISPLAY 1.021277 (-6000 -4225);
PAINT WHITE (-6000 -4225);
FORCENOTE
PVCCIN_CPU0_PHASE7
(-5950 -1400) 0;
DISPLAY LEFT (-5950 -1400);
DISPLAY 1.021277 (-5950 -1400);
PAINT WHITE (-5950 -1400);
FORCENOTE
PGL6303.151HLT 
(-2825 -5000) 0;
DISPLAY LEFT (-2825 -5000);
DISPLAY 1.021277 (-2825 -5000);
FORCENOTE
DCR=2-3,0.27M OHM
(-2825 -5300) 0;
DISPLAY LEFT (-2825 -5300);
DISPLAY 1.021277 (-2825 -5300);
FORCENOTE
DCR=1-4,0.105M OHM
(-2825 -5225) 0;
DISPLAY LEFT (-2825 -5225);
DISPLAY 1.021277 (-2825 -5225);
FORCENOTE
ISAT=70A@100C
(-2825 -5150) 0;
DISPLAY LEFT (-2825 -5150);
DISPLAY 1.021277 (-2825 -5150);
FORCENOTE
11.0*7.5*12.5
(-2825 -5075) 0;
DISPLAY LEFT (-2825 -5075);
DISPLAY 1.021277 (-2825 -5075);
FORCENOTE
DCR=2-3,0.27M OHM
(-2925 -2500) 0;
DISPLAY LEFT (-2925 -2500);
DISPLAY 1.021277 (-2925 -2500);
FORCENOTE
PGL6303.151HLT 
(-2925 -2200) 0;
DISPLAY LEFT (-2925 -2200);
DISPLAY 1.021277 (-2925 -2200);
FORCENOTE
11.0*7.5*12.5
(-2925 -2275) 0;
DISPLAY LEFT (-2925 -2275);
DISPLAY 1.021277 (-2925 -2275);
FORCENOTE
ISAT=70A@100C
(-2925 -2350) 0;
DISPLAY LEFT (-2925 -2350);
DISPLAY 1.021277 (-2925 -2350);
FORCENOTE
DCR=1-4,0.105M OHM
(-2925 -2425) 0;
DISPLAY LEFT (-2925 -2425);
DISPLAY 1.021277 (-2925 -2425);
QUIT
